FILE_TYPE = MACRO_DRAWING;
SET COLOR_WIRE YELLOW;
SET COLOR_PROP ORANGE;
SET COLOR_DOT WHITE;
SET COLOR_ARC YELLOW;
SET COLOR_BODY GREEN;
SET COLOR_NOTE PURPLE;
SET PROP_DISPLAY VALUE;
SET PAGE_NUMBER P523;
FORCEADD CAPACITOR..2
(-9250 3100);
FORCEPROP 1 LAST $LOCATION C264
J 0
(-9150 2950);
DISPLAY 1.212766 (-9150 2950);
PAINT GREEN (-9150 2950);
FORCEPROP 0 LAST CDS_LOCATION C264
J 0
(-9200 2950);
DISPLAY 1.212766 (-9200 2950);
PAINT GREEN (-9200 2950);
DISPLAY INVISIBLE (-9200 2950);
FORCEPROP 0 LAST $SEC 1
J 0
(-9200 3250);
DISPLAY 0.680851 (-9200 3250);
PAINT MONO (-9200 3250);
DISPLAY INVISIBLE (-9200 3250);
FORCEPROP 0 LAST CDS_SEC 1
J 0
(-9200 3250);
DISPLAY 1.021277 (-9200 3250);
DISPLAY INVISIBLE (-9200 3250);
FORCEPROP 0 LASTPIN (-9250 3200) $PN 1
R 1
J 0
(-9260 3210);
DISPLAY 0.680851 (-9260 3210);
PAINT MONO (-9260 3210);
FORCEPROP 0 LASTPIN (-9250 2950) $PN 2
R 1
J 2
(-9260 2940);
DISPLAY 0.680851 (-9260 2940);
PAINT MONO (-9260 2940);
FORCEPROP 1 LAST PATH I10
J 0
(-9350 3150);
DISPLAY 1.212766 (-9350 3150);
PAINT GREEN (-9350 3150);
DISPLAY INVISIBLE (-9350 3150);
FORCEPROP 1 LAST TOLERANCE 5%
J 0
(-9400 3200);
DISPLAY 1.212766 (-9400 3200);
PAINT GREEN (-9400 3200);
DISPLAY INVISIBLE (-9400 3200);
FORCEPROP 2 LAST CDS_LIB passive
J 0
(-9250 3100);
DISPLAY INVISIBLE (-9250 3100);
FORCEPROP 1 LAST CDS_LMAN_SYM_OUTLINE -50,0,50,-50
J 0
(-9250 3100);
DISPLAY 0.468085 (-9250 3100);
PAINT GREEN (-9250 3100);
DISPLAY INVISIBLE (-9250 3100);
FORCEPROP 1 LAST CLS_PN G104-0A180-FJ
J 0
(-9350 3150);
DISPLAY 1.212766 (-9350 3150);
PAINT GREEN (-9350 3150);
DISPLAY INVISIBLE (-9350 3150);
FORCEPROP 1 LAST VALUE 18PF
J 0
(-9150 3050);
DISPLAY 1.212766 (-9150 3050);
PAINT GREEN (-9150 3050);
FORCEPROP 0 LAST PACKAGE 0201
J 0
(-9150 3150);
DISPLAY 1.021277 (-9150 3150);
FORCEPROP 0 LAST VOLTAGE 25V
J 0
(-9150 3250);
DISPLAY 1.021277 (-9150 3250);
FORCEADD RESISTOR..1
(-12300 2500);
FORCEPROP 1 LAST $LOCATION R245
J 2
(-12401 2555);
DISPLAY 1.212766 (-12401 2555);
PAINT GREEN (-12401 2555);
FORCEPROP 0 LAST CDS_LOCATION R245
J 0
(-12250 2650);
DISPLAY 1.021277 (-12250 2650);
DISPLAY INVISIBLE (-12250 2650);
FORCEPROP 0 LAST $SEC 1
J 0
(-12250 2650);
DISPLAY 0.680851 (-12250 2650);
PAINT MONO (-12250 2650);
DISPLAY INVISIBLE (-12250 2650);
FORCEPROP 0 LAST CDS_SEC 1
J 0
(-12250 2650);
DISPLAY 1.021277 (-12250 2650);
DISPLAY INVISIBLE (-12250 2650);
FORCEPROP 0 LASTPIN (-12400 2500) $PN 1
J 2
(-12410 2510);
DISPLAY 0.680851 (-12410 2510);
PAINT MONO (-12410 2510);
FORCEPROP 0 LASTPIN (-12150 2500) $PN 2
J 0
(-12140 2510);
DISPLAY 0.680851 (-12140 2510);
PAINT MONO (-12140 2510);
FORCEPROP 1 LAST CLS_PN G155-100R0-J0
J 0
(-12436 2700);
DISPLAY 1.212766 (-12436 2700);
PAINT GREEN (-12436 2700);
DISPLAY INVISIBLE (-12436 2700);
FORCEPROP 1 LAST CDS_LMAN_SYM_OUTLINE -50,50,100,-50
J 0
(-12300 2500);
DISPLAY 0.468085 (-12300 2500);
PAINT GREEN (-12300 2500);
DISPLAY INVISIBLE (-12300 2500);
FORCEPROP 2 LAST CDS_LIB passive
J 0
(-12300 2500);
DISPLAY INVISIBLE (-12300 2500);
FORCEPROP 1 LAST TOLERANCE -
J 0
(-12497 2755);
DISPLAY 1.212766 (-12497 2755);
PAINT GREEN (-12497 2755);
DISPLAY INVISIBLE (-12497 2755);
FORCEPROP 1 LAST PATH I104
J 0
(-12497 2605);
DISPLAY 1.212766 (-12497 2605);
PAINT GREEN (-12497 2605);
DISPLAY INVISIBLE (-12497 2605);
FORCEPROP 0 LAST PACKAGE 0402
J 0
(-12350 2400);
DISPLAY 1.021277 (-12350 2400);
FORCEPROP 1 LAST VALUE 0OHM
J 0
(-12261 2555);
DISPLAY 1.212766 (-12261 2555);
PAINT GREEN (-12261 2555);
FORCEADD OFFPAGE_OUT..1
R 4
(-13500 2500);
FORCEPROP 2 LAST $XR0 25F6<> 
J 0
(-13714 2500);
DISPLAY 0.638298 (-13714 2500);
PAINT MONO (-13714 2500);
FORCEPROP 2 LAST $XR1 30D2< 
J 0
(-13894 2500);
DISPLAY 0.638298 (-13894 2500);
PAINT MONO (-13894 2500);
FORCEPROP 2 LAST PATH I105
R 2
J 0
(-13550 2400);
DISPLAY 1.021277 (-13550 2400);
DISPLAY INVISIBLE (-13550 2400);
FORCEPROP 1 LAST OFFPAGE TRUE
R 2
J 0
(-13510 2445);
DISPLAY 0.808511 (-13510 2445);
PAINT GREEN (-13510 2445);
DISPLAY INVISIBLE (-13510 2445);
FORCEPROP 1 LAST BODY_TYPE COMMENT
R 2
J 0
(-13510 2365);
DISPLAY 0.808511 (-13510 2365);
PAINT GREEN (-13510 2365);
DISPLAY INVISIBLE (-13510 2365);
FORCEPROP 1 LAST CDS_LMAN_SYM_OUTLINE -50,50,50,-50
R 2
J 0
(-13500 2500);
DISPLAY 0.468085 (-13500 2500);
PAINT GREEN (-13500 2500);
DISPLAY INVISIBLE (-13500 2500);
FORCEPROP 2 LAST CDS_LIB cls
R 2
J 0
(-13500 2500);
DISPLAY INVISIBLE (-13500 2500);
FORCEADD GND_SG..1
(-11600 2300);
FORCEPROP 3 LASTPIN (-11550 2350) SIG_NAME SG\g
J 0
(-11540 2360);
DISPLAY 0.659574 (-11540 2360);
PAINT MONO (-11540 2360);
DISPLAY INVISIBLE (-11540 2360);
FORCEPROP 1 LAST PATH I106
J 0
(-11565 2300);
DISPLAY 0.808511 (-11565 2300);
PAINT GREEN (-11565 2300);
DISPLAY INVISIBLE (-11565 2300);
FORCEPROP 1 LAST BODY_TYPE PLUMBING
J 0
(-11585 2285);
DISPLAY 0.808511 (-11585 2285);
PAINT GREEN (-11585 2285);
DISPLAY INVISIBLE (-11585 2285);
FORCEPROP 2 LAST CDS_LIB cls
J 0
(-11600 2300);
DISPLAY INVISIBLE (-11600 2300);
FORCEPROP 1 LAST CDS_LMAN_SYM_OUTLINE 0,0,100,-50
J 0
(-11600 2300);
DISPLAY 0.468085 (-11600 2300);
PAINT GREEN (-11600 2300);
DISPLAY INVISIBLE (-11600 2300);
FORCEPROP 1 LAST HDL_POWER SG
J 1
(-11545 2205);
DISPLAY 0.808511 (-11545 2205);
PAINT GREEN (-11545 2205);
FORCEADD OFFPAGE_IN..2
R 2
(-13700 4250);
FORCEPROP 2 LAST $XR0 25F6<> 
J 0
(-13914 4250);
DISPLAY 0.638298 (-13914 4250);
PAINT MONO (-13914 4250);
FORCEPROP 2 LAST $XR1 28H6> 
J 0
(-14094 4250);
DISPLAY 0.638298 (-14094 4250);
PAINT MONO (-14094 4250);
FORCEPROP 2 LAST PATH I108
J 0
(-13650 4350);
DISPLAY 1.021277 (-13650 4350);
DISPLAY INVISIBLE (-13650 4350);
FORCEPROP 1 LAST OFFPAGE TRUE
J 2
(-13710 4305);
DISPLAY 0.808511 (-13710 4305);
PAINT GREEN (-13710 4305);
DISPLAY INVISIBLE (-13710 4305);
FORCEPROP 2 LAST CDS_LIB cls
J 0
(-13700 4250);
DISPLAY INVISIBLE (-13700 4250);
FORCEPROP 1 LAST CDS_LMAN_SYM_OUTLINE -50,50,50,-50
J 2
(-13700 4250);
DISPLAY 0.468085 (-13700 4250);
PAINT GREEN (-13700 4250);
DISPLAY INVISIBLE (-13700 4250);
FORCEPROP 1 LAST BODY_TYPE COMMENT
J 2
(-13710 4385);
DISPLAY 0.808511 (-13710 4385);
PAINT GREEN (-13710 4385);
DISPLAY INVISIBLE (-13710 4385);
FORCEADD RESISTOR..1
(-12600 4250);
FORCEPROP 1 LAST $LOCATION R244
J 2
(-12701 4305);
DISPLAY 1.212766 (-12701 4305);
PAINT GREEN (-12701 4305);
FORCEPROP 0 LAST CDS_LOCATION R244
J 0
(-12550 4400);
DISPLAY 1.021277 (-12550 4400);
DISPLAY INVISIBLE (-12550 4400);
FORCEPROP 0 LAST $SEC 1
J 0
(-12550 4400);
DISPLAY 0.680851 (-12550 4400);
PAINT MONO (-12550 4400);
DISPLAY INVISIBLE (-12550 4400);
FORCEPROP 0 LAST CDS_SEC 1
J 0
(-12550 4400);
DISPLAY 1.021277 (-12550 4400);
DISPLAY INVISIBLE (-12550 4400);
FORCEPROP 0 LASTPIN (-12700 4250) $PN 1
J 2
(-12710 4260);
DISPLAY 0.680851 (-12710 4260);
PAINT MONO (-12710 4260);
FORCEPROP 0 LASTPIN (-12450 4250) $PN 2
J 0
(-12440 4260);
DISPLAY 0.680851 (-12440 4260);
PAINT MONO (-12440 4260);
FORCEPROP 1 LAST PATH I109
J 0
(-12797 4355);
DISPLAY 1.212766 (-12797 4355);
PAINT GREEN (-12797 4355);
DISPLAY INVISIBLE (-12797 4355);
FORCEPROP 1 LAST TOLERANCE -
J 0
(-12797 4505);
DISPLAY 1.212766 (-12797 4505);
PAINT GREEN (-12797 4505);
DISPLAY INVISIBLE (-12797 4505);
FORCEPROP 2 LAST CDS_LIB passive
J 0
(-12600 4250);
DISPLAY INVISIBLE (-12600 4250);
FORCEPROP 1 LAST CDS_LMAN_SYM_OUTLINE -50,50,100,-50
J 0
(-12600 4250);
DISPLAY 0.468085 (-12600 4250);
PAINT GREEN (-12600 4250);
DISPLAY INVISIBLE (-12600 4250);
FORCEPROP 1 LAST CLS_PN G155-100R0-J0
J 0
(-12736 4450);
DISPLAY 1.212766 (-12736 4450);
PAINT GREEN (-12736 4450);
DISPLAY INVISIBLE (-12736 4450);
FORCEPROP 1 LAST VALUE 0OHM
J 0
(-12561 4305);
DISPLAY 1.212766 (-12561 4305);
PAINT GREEN (-12561 4305);
FORCEPROP 0 LAST PACKAGE 0402
J 0
(-12550 4450);
DISPLAY 1.021277 (-12550 4450);
FORCEADD TPS54824RNVR_VQFN18..1
(-8650 4650);
FORCEPROP 1 LAST $LOCATION U26
J 0
(-8600 4750);
DISPLAY 1.212766 (-8600 4750);
PAINT GREEN (-8600 4750);
FORCEPROP 0 LAST CDS_LOCATION U26
J 0
(-8600 4750);
DISPLAY 1.212766 (-8600 4750);
PAINT GREEN (-8600 4750);
DISPLAY INVISIBLE (-8600 4750);
FORCEPROP 0 LAST $SEC 1
J 0
(-8600 5050);
DISPLAY 0.680851 (-8600 5050);
PAINT MONO (-8600 5050);
DISPLAY INVISIBLE (-8600 5050);
FORCEPROP 0 LAST CDS_SEC 1
J 0
(-8600 5050);
DISPLAY 1.021277 (-8600 5050);
DISPLAY INVISIBLE (-8600 5050);
FORCEPROP 0 LASTPIN (-8750 3050) $PN 12
J 2
(-8760 3060);
DISPLAY 0.680851 (-8760 3060);
PAINT MONO (-8760 3060);
FORCEPROP 0 LASTPIN (-7550 4550) $PN 1
J 0
(-7540 4560);
DISPLAY 0.680851 (-7540 4560);
PAINT MONO (-7540 4560);
FORCEPROP 0 LASTPIN (-8750 3450) $PN 15
J 2
(-8760 3460);
DISPLAY 0.680851 (-8760 3460);
PAINT MONO (-8760 3460);
FORCEPROP 0 LASTPIN (-8750 4250) $PN 17
J 2
(-8760 4260);
DISPLAY 0.680851 (-8760 4260);
PAINT MONO (-8760 4260);
FORCEPROP 0 LASTPIN (-7550 3850) $PN 14
J 0
(-7540 3860);
DISPLAY 0.680851 (-7540 3860);
PAINT MONO (-7540 3860);
FORCEPROP 0 LASTPIN (-7550 3550) $PN 3
J 0
(-7540 3560);
DISPLAY 0.680851 (-7540 3560);
PAINT MONO (-7540 3560);
FORCEPROP 0 LASTPIN (-7550 3450) $PN 4
J 0
(-7540 3460);
DISPLAY 0.680851 (-7540 3460);
PAINT MONO (-7540 3460);
FORCEPROP 0 LASTPIN (-7550 3350) $PN 5
J 0
(-7540 3360);
DISPLAY 0.680851 (-7540 3360);
PAINT MONO (-7540 3360);
FORCEPROP 0 LASTPIN (-7550 3250) $PN 8
J 0
(-7540 3260);
DISPLAY 0.680851 (-7540 3260);
PAINT MONO (-7540 3260);
FORCEPROP 0 LASTPIN (-7550 3150) $PN 9
J 0
(-7540 3160);
DISPLAY 0.680851 (-7540 3160);
PAINT MONO (-7540 3160);
FORCEPROP 0 LASTPIN (-7550 3050) $PN 10
J 0
(-7540 3060);
DISPLAY 0.680851 (-7540 3060);
PAINT MONO (-7540 3060);
FORCEPROP 0 LASTPIN (-8750 4050) $PN 18
J 2
(-8760 4060);
DISPLAY 0.680851 (-8760 4060);
PAINT MONO (-8760 4060);
FORCEPROP 0 LASTPIN (-8750 3650) $PN 13
J 2
(-8760 3660);
DISPLAY 0.680851 (-8760 3660);
PAINT MONO (-8760 3660);
FORCEPROP 0 LASTPIN (-8750 3850) $PN 16
J 2
(-8760 3860);
DISPLAY 0.680851 (-8760 3860);
PAINT MONO (-8760 3860);
FORCEPROP 0 LASTPIN (-7550 4350) $PN 6
J 0
(-7540 4360);
DISPLAY 0.680851 (-7540 4360);
PAINT MONO (-7540 4360);
FORCEPROP 0 LASTPIN (-7550 4250) $PN 7
J 0
(-7540 4260);
DISPLAY 0.680851 (-7540 4260);
PAINT MONO (-7540 4260);
FORCEPROP 0 LASTPIN (-8750 4550) $PN 2
J 2
(-8760 4560);
DISPLAY 0.680851 (-8760 4560);
PAINT MONO (-8760 4560);
FORCEPROP 0 LASTPIN (-8750 4450) $PN 11
J 2
(-8760 4460);
DISPLAY 0.680851 (-8760 4460);
PAINT MONO (-8760 4460);
FORCEPROP 1 LAST PATH I11
J 0
(-8600 4700);
DISPLAY 1.212766 (-8600 4700);
PAINT GREEN (-8600 4700);
DISPLAY INVISIBLE (-8600 4700);
FORCEPROP 1 LAST CDS_LMAN_SYM_OUTLINE 0,0,1000,-1750
J 0
(-8650 4650);
DISPLAY 0.468085 (-8650 4650);
PAINT GREEN (-8650 4650);
DISPLAY INVISIBLE (-8650 4650);
FORCEPROP 2 LAST CDS_LIB stdlogic
J 0
(-8650 4650);
DISPLAY INVISIBLE (-8650 4650);
FORCEPROP 1 LAST VALUE TPS54424RNVT
J 0
(-8600 4950);
DISPLAY 1.212766 (-8600 4950);
PAINT GREEN (-8600 4950);
FORCEPROP 1 LAST CLS_PN G220-10657-01
J 0
(-8600 4850);
DISPLAY 1.212766 (-8600 4850);
PAINT GREEN (-8600 4850);
FORCEADD CAPACITOR..2
(-11050 3350);
FORCEPROP 1 LAST $LOCATION C259
J 0
(-10900 3250);
DISPLAY 1.212766 (-10900 3250);
PAINT GREEN (-10900 3250);
FORCEPROP 0 LAST CDS_LOCATION C259
J 0
(-11000 3200);
DISPLAY 1.212766 (-11000 3200);
PAINT GREEN (-11000 3200);
DISPLAY INVISIBLE (-11000 3200);
FORCEPROP 0 LAST $SEC 1
J 0
(-11000 3500);
DISPLAY 0.680851 (-11000 3500);
PAINT MONO (-11000 3500);
DISPLAY INVISIBLE (-11000 3500);
FORCEPROP 0 LAST CDS_SEC 1
J 0
(-11000 3500);
DISPLAY 1.021277 (-11000 3500);
DISPLAY INVISIBLE (-11000 3500);
FORCEPROP 0 LASTPIN (-11050 3450) $PN 1
R 1
J 0
(-11060 3460);
DISPLAY 0.680851 (-11060 3460);
PAINT MONO (-11060 3460);
FORCEPROP 0 LASTPIN (-11050 3200) $PN 2
R 1
J 2
(-11060 3190);
DISPLAY 0.680851 (-11060 3190);
PAINT MONO (-11060 3190);
FORCEPROP 1 LAST PATH I12
J 0
(-11150 3400);
DISPLAY 1.212766 (-11150 3400);
PAINT GREEN (-11150 3400);
DISPLAY INVISIBLE (-11150 3400);
FORCEPROP 1 LAST CLS_PN G105-0B223-EK
J 0
(-11150 3400);
DISPLAY 1.212766 (-11150 3400);
PAINT GREEN (-11150 3400);
DISPLAY INVISIBLE (-11150 3400);
FORCEPROP 1 LAST CDS_LMAN_SYM_OUTLINE -50,0,50,-50
J 0
(-11050 3350);
DISPLAY 0.468085 (-11050 3350);
PAINT GREEN (-11050 3350);
DISPLAY INVISIBLE (-11050 3350);
FORCEPROP 2 LAST CDS_LIB passive
J 0
(-11050 3350);
DISPLAY INVISIBLE (-11050 3350);
FORCEPROP 1 LAST TOLERANCE 10%
J 0
(-11200 3450);
DISPLAY 1.212766 (-11200 3450);
PAINT GREEN (-11200 3450);
DISPLAY INVISIBLE (-11200 3450);
FORCEPROP 1 LAST VALUE 0.022UF
J 0
(-10950 3350);
DISPLAY 1.212766 (-10950 3350);
PAINT GREEN (-10950 3350);
FORCEPROP 0 LAST PACKAGE 0402
J 0
(-10900 3450);
DISPLAY 1.021277 (-10900 3450);
FORCEPROP 0 LAST VOLTAGE 25V
J 0
(-10900 3550);
DISPLAY 1.021277 (-10900 3550);
FORCEADD CAPACITOR..2
(-11450 5200);
FORCEPROP 1 LAST $LOCATION C257
J 0
(-11400 5250);
DISPLAY 1.212766 (-11400 5250);
PAINT GREEN (-11400 5250);
FORCEPROP 0 LAST CDS_LOCATION C257
J 0
(-11400 5450);
DISPLAY INVISIBLE (-11400 5450);
FORCEPROP 0 LAST $SEC 1
J 0
(-11400 5350);
DISPLAY INVISIBLE (-11400 5350);
FORCEPROP 0 LAST CDS_SEC 1
J 0
(-11400 5350);
DISPLAY INVISIBLE (-11400 5350);
FORCEPROP 0 LASTPIN (-11450 5300) $PN 1
R 1
J 0
(-11460 5310);
DISPLAY 0.808511 (-11460 5310);
FORCEPROP 0 LASTPIN (-11450 5050) $PN 2
R 1
J 2
(-11460 5040);
DISPLAY 0.808511 (-11460 5040);
FORCEPROP 1 LAST PATH I13
J 0
(-11550 5250);
DISPLAY 1.212766 (-11550 5250);
PAINT GREEN (-11550 5250);
DISPLAY INVISIBLE (-11550 5250);
FORCEPROP 1 LAST TOLERANCE 20%
J 0
(-11600 5300);
DISPLAY 1.212766 (-11600 5300);
PAINT GREEN (-11600 5300);
DISPLAY INVISIBLE (-11600 5300);
FORCEPROP 2 LAST CDS_LIB passive
J 0
(-11450 5200);
DISPLAY INVISIBLE (-11450 5200);
FORCEPROP 1 LAST CDS_LMAN_SYM_OUTLINE -50,0,50,-50
J 0
(-11450 5200);
DISPLAY 0.468085 (-11450 5200);
PAINT GREEN (-11450 5200);
DISPLAY INVISIBLE (-11450 5200);
FORCEPROP 1 LAST CLS_PN G107-0F106-EM
J 0
(-11550 5250);
DISPLAY 1.212766 (-11550 5250);
PAINT GREEN (-11550 5250);
DISPLAY INVISIBLE (-11550 5250);
FORCEPROP 0 LAST PACKAGE 0805
J 0
(-11400 5400);
DISPLAY 1.021277 (-11400 5400);
FORCEPROP 0 LAST VOLTAGE 25V
J 0
(-11400 5500);
DISPLAY 1.021277 (-11400 5500);
FORCEPROP 1 LAST VALUE 10UF
J 0
(-11400 5150);
DISPLAY 1.212766 (-11400 5150);
PAINT GREEN (-11400 5150);
FORCEADD CAPACITOR..2
(-11000 5200);
FORCEPROP 1 LAST $LOCATION C260
J 0
(-10950 5250);
DISPLAY 1.212766 (-10950 5250);
PAINT GREEN (-10950 5250);
FORCEPROP 0 LAST CDS_LOCATION C260
J 0
(-10950 5450);
DISPLAY INVISIBLE (-10950 5450);
FORCEPROP 0 LAST $SEC 1
J 0
(-10950 5350);
DISPLAY INVISIBLE (-10950 5350);
FORCEPROP 0 LAST CDS_SEC 1
J 0
(-10950 5350);
DISPLAY INVISIBLE (-10950 5350);
FORCEPROP 0 LASTPIN (-11000 5300) $PN 1
R 1
J 0
(-11010 5310);
DISPLAY 0.808511 (-11010 5310);
FORCEPROP 0 LASTPIN (-11000 5050) $PN 2
R 1
J 2
(-11010 5040);
DISPLAY 0.808511 (-11010 5040);
FORCEPROP 1 LAST PATH I14
J 0
(-11100 5250);
DISPLAY 1.212766 (-11100 5250);
PAINT GREEN (-11100 5250);
DISPLAY INVISIBLE (-11100 5250);
FORCEPROP 1 LAST TOLERANCE 20%
J 0
(-11150 5300);
DISPLAY 1.212766 (-11150 5300);
PAINT GREEN (-11150 5300);
DISPLAY INVISIBLE (-11150 5300);
FORCEPROP 1 LAST CLS_PN G107-0F106-EM
J 0
(-11100 5250);
DISPLAY 1.212766 (-11100 5250);
PAINT GREEN (-11100 5250);
DISPLAY INVISIBLE (-11100 5250);
FORCEPROP 1 LAST CDS_LMAN_SYM_OUTLINE -50,0,50,-50
J 0
(-11000 5200);
DISPLAY 0.468085 (-11000 5200);
PAINT GREEN (-11000 5200);
DISPLAY INVISIBLE (-11000 5200);
FORCEPROP 2 LAST CDS_LIB passive
J 0
(-11000 5200);
DISPLAY INVISIBLE (-11000 5200);
FORCEPROP 0 LAST PACKAGE 0805
J 0
(-10950 5400);
DISPLAY 1.021277 (-10950 5400);
FORCEPROP 1 LAST VALUE 10UF
J 0
(-10950 5150);
DISPLAY 1.212766 (-10950 5150);
PAINT GREEN (-10950 5150);
FORCEPROP 0 LAST VOLTAGE 25V
J 0
(-10950 5500);
DISPLAY 1.021277 (-10950 5500);
FORCEADD RESISTOR..2
(-10500 3350);
FORCEPROP 1 LAST $LOCATION R248
J 0
(-10450 3200);
DISPLAY 1.212766 (-10450 3200);
PAINT GREEN (-10450 3200);
FORCEPROP 0 LAST CDS_LOCATION R248
J 0
(-10450 3200);
DISPLAY 1.212766 (-10450 3200);
PAINT GREEN (-10450 3200);
DISPLAY INVISIBLE (-10450 3200);
FORCEPROP 0 LAST $SEC 1
J 0
(-10450 3500);
DISPLAY 0.680851 (-10450 3500);
PAINT MONO (-10450 3500);
DISPLAY INVISIBLE (-10450 3500);
FORCEPROP 0 LAST CDS_SEC 1
J 0
(-10450 3500);
DISPLAY 1.021277 (-10450 3500);
DISPLAY INVISIBLE (-10450 3500);
FORCEPROP 0 LASTPIN (-10500 3450) $PN 1
R 1
J 0
(-10510 3460);
DISPLAY 0.680851 (-10510 3460);
PAINT MONO (-10510 3460);
FORCEPROP 0 LASTPIN (-10500 3200) $PN 2
R 1
J 2
(-10510 3190);
DISPLAY 0.680851 (-10510 3190);
PAINT MONO (-10510 3190);
FORCEPROP 1 LAST PATH I15
J 0
(-10697 3455);
DISPLAY 1.212766 (-10697 3455);
PAINT GREEN (-10697 3455);
DISPLAY INVISIBLE (-10697 3455);
FORCEPROP 1 LAST TOLERANCE 1%
J 0
(-10697 3605);
DISPLAY 1.212766 (-10697 3605);
PAINT GREEN (-10697 3605);
DISPLAY INVISIBLE (-10697 3605);
FORCEPROP 1 LAST CLS_PN G155-11003-01
J 0
(-10636 3550);
DISPLAY 1.212766 (-10636 3550);
PAINT GREEN (-10636 3550);
DISPLAY INVISIBLE (-10636 3550);
FORCEPROP 2 LAST CDS_LIB passive
J 0
(-10500 3350);
DISPLAY INVISIBLE (-10500 3350);
FORCEPROP 1 LAST CDS_LMAN_SYM_OUTLINE -50,50,50,-100
J 0
(-10500 3350);
DISPLAY 0.468085 (-10500 3350);
PAINT GREEN (-10500 3350);
DISPLAY INVISIBLE (-10500 3350);
FORCEPROP 0 LAST PACKAGE 0402
J 0
(-10350 3300);
DISPLAY 1.021277 (-10350 3300);
FORCEPROP 1 LAST VALUE 100KOHM
J 0
(-10450 3400);
DISPLAY 1.212766 (-10450 3400);
PAINT GREEN (-10450 3400);
FORCEADD RESISTOR..2
(-9850 3250);
FORCEPROP 1 LAST $LOCATION R249
J 0
(-9800 3250);
DISPLAY 1.212766 (-9800 3250);
PAINT GREEN (-9800 3250);
FORCEPROP 0 LAST CDS_LOCATION R249
J 0
(-9800 3100);
DISPLAY 1.212766 (-9800 3100);
PAINT GREEN (-9800 3100);
DISPLAY INVISIBLE (-9800 3100);
FORCEPROP 0 LAST $SEC 1
J 0
(-9800 3400);
DISPLAY 0.680851 (-9800 3400);
PAINT MONO (-9800 3400);
DISPLAY INVISIBLE (-9800 3400);
FORCEPROP 0 LAST CDS_SEC 1
J 0
(-9800 3400);
DISPLAY 1.021277 (-9800 3400);
DISPLAY INVISIBLE (-9800 3400);
FORCEPROP 0 LASTPIN (-9850 3350) $PN 1
R 1
J 0
(-9860 3360);
DISPLAY 0.680851 (-9860 3360);
PAINT MONO (-9860 3360);
FORCEPROP 0 LASTPIN (-9850 3100) $PN 2
R 1
J 2
(-9860 3090);
DISPLAY 0.680851 (-9860 3090);
PAINT MONO (-9860 3090);
FORCEPROP 2 LAST CDS_LIB passive
J 0
(-9850 3250);
DISPLAY INVISIBLE (-9850 3250);
FORCEPROP 1 LAST CDS_LMAN_SYM_OUTLINE -50,50,50,-100
J 0
(-9850 3250);
DISPLAY 0.468085 (-9850 3250);
PAINT GREEN (-9850 3250);
DISPLAY INVISIBLE (-9850 3250);
FORCEPROP 1 LAST TOLERANCE 1%
J 0
(-10047 3505);
DISPLAY 1.212766 (-10047 3505);
PAINT GREEN (-10047 3505);
DISPLAY INVISIBLE (-10047 3505);
FORCEPROP 1 LAST PATH I16
J 0
(-10047 3355);
DISPLAY 1.212766 (-10047 3355);
PAINT GREEN (-10047 3355);
DISPLAY INVISIBLE (-10047 3355);
FORCEPROP 1 LAST CLS_PN G155-14701-01
J 0
(-9986 3450);
DISPLAY 1.212766 (-9986 3450);
PAINT GREEN (-9986 3450);
DISPLAY INVISIBLE (-9986 3450);
FORCEPROP 0 LAST PACKAGE 0402
J 0
(-9550 3300);
DISPLAY 1.021277 (-9550 3300);
FORCEPROP 1 LAST VALUE 4.7KOHM
J 0
(-9800 3150);
DISPLAY 1.212766 (-9800 3150);
PAINT GREEN (-9800 3150);
FORCEADD CAPACITOR..2
(-10550 5200);
FORCEPROP 1 LAST $LOCATION C261
J 0
(-10400 5250);
DISPLAY 1.212766 (-10400 5250);
PAINT GREEN (-10400 5250);
FORCEPROP 0 LAST CDS_LOCATION C261
J 0
(-10400 5350);
DISPLAY 1.021277 (-10400 5350);
DISPLAY INVISIBLE (-10400 5350);
FORCEPROP 0 LAST $SEC 1
J 0
(-10400 5350);
DISPLAY 0.680851 (-10400 5350);
PAINT MONO (-10400 5350);
DISPLAY INVISIBLE (-10400 5350);
FORCEPROP 0 LAST CDS_SEC 1
J 0
(-10400 5350);
DISPLAY 1.021277 (-10400 5350);
DISPLAY INVISIBLE (-10400 5350);
FORCEPROP 0 LASTPIN (-10550 5300) $PN 1
R 1
J 0
(-10560 5310);
DISPLAY 0.680851 (-10560 5310);
PAINT MONO (-10560 5310);
FORCEPROP 0 LASTPIN (-10550 5050) $PN 2
R 1
J 2
(-10560 5040);
DISPLAY 0.680851 (-10560 5040);
PAINT MONO (-10560 5040);
FORCEPROP 1 LAST PATH I17
J 0
(-10650 5250);
DISPLAY 1.212766 (-10650 5250);
PAINT GREEN (-10650 5250);
DISPLAY INVISIBLE (-10650 5250);
FORCEPROP 1 LAST TOLERANCE 10%
J 0
(-10700 5300);
DISPLAY 1.212766 (-10700 5300);
PAINT GREEN (-10700 5300);
DISPLAY INVISIBLE (-10700 5300);
FORCEPROP 2 LAST CDS_LIB passive
J 0
(-10550 5200);
DISPLAY INVISIBLE (-10550 5200);
FORCEPROP 1 LAST CDS_LMAN_SYM_OUTLINE -50,0,50,-50
J 0
(-10550 5200);
DISPLAY 0.468085 (-10550 5200);
PAINT GREEN (-10550 5200);
DISPLAY INVISIBLE (-10550 5200);
FORCEPROP 1 LAST CLS_PN G105-0B104-EK
J 0
(-10650 5250);
DISPLAY 1.212766 (-10650 5250);
PAINT GREEN (-10650 5250);
DISPLAY INVISIBLE (-10650 5250);
FORCEPROP 0 LAST PACKAGE 0402
J 0
(-10400 5400);
DISPLAY 1.021277 (-10400 5400);
FORCEPROP 1 LAST VALUE 0.1UF
J 0
(-10450 5150);
DISPLAY 1.212766 (-10450 5150);
PAINT GREEN (-10450 5150);
FORCEPROP 0 LAST VOLTAGE 25V
J 0
(-10400 5500);
DISPLAY 1.021277 (-10400 5500);
FORCEADD GND_SG..1
(-10050 4650);
FORCEPROP 3 LASTPIN (-10000 4700) SIG_NAME SG\g
J 0
(-9990 4710);
DISPLAY 0.659574 (-9990 4710);
PAINT MONO (-9990 4710);
DISPLAY INVISIBLE (-9990 4710);
FORCEPROP 1 LAST PATH I18
J 0
(-10015 4650);
DISPLAY 0.808511 (-10015 4650);
PAINT GREEN (-10015 4650);
DISPLAY INVISIBLE (-10015 4650);
FORCEPROP 1 LAST BODY_TYPE PLUMBING
J 0
(-10035 4635);
DISPLAY 0.808511 (-10035 4635);
PAINT GREEN (-10035 4635);
DISPLAY INVISIBLE (-10035 4635);
FORCEPROP 2 LAST CDS_LIB cls
J 0
(-10050 4650);
DISPLAY INVISIBLE (-10050 4650);
FORCEPROP 1 LAST CDS_LMAN_SYM_OUTLINE 0,0,100,-50
J 0
(-10050 4650);
DISPLAY 0.468085 (-10050 4650);
PAINT GREEN (-10050 4650);
DISPLAY INVISIBLE (-10050 4650);
FORCEPROP 1 LAST HDL_POWER SG
J 1
(-9995 4555);
DISPLAY 0.808511 (-9995 4555);
PAINT GREEN (-9995 4555);
FORCEADD CAPACITOR..2
(-10000 5200);
FORCEPROP 1 LAST $LOCATION C262
J 0
(-9850 5250);
DISPLAY 1.212766 (-9850 5250);
PAINT GREEN (-9850 5250);
FORCEPROP 0 LAST CDS_LOCATION C262
J 0
(-9900 5250);
DISPLAY 1.021277 (-9900 5250);
DISPLAY INVISIBLE (-9900 5250);
FORCEPROP 0 LAST $SEC 1
J 0
(-9900 5250);
DISPLAY 0.680851 (-9900 5250);
PAINT MONO (-9900 5250);
DISPLAY INVISIBLE (-9900 5250);
FORCEPROP 0 LAST CDS_SEC 1
J 0
(-9900 5250);
DISPLAY 1.021277 (-9900 5250);
DISPLAY INVISIBLE (-9900 5250);
FORCEPROP 0 LASTPIN (-10000 5300) $PN 1
R 1
J 0
(-10010 5310);
DISPLAY 0.680851 (-10010 5310);
PAINT MONO (-10010 5310);
FORCEPROP 0 LASTPIN (-10000 5050) $PN 2
R 1
J 2
(-10010 5040);
DISPLAY 0.680851 (-10010 5040);
PAINT MONO (-10010 5040);
FORCEPROP 1 LAST PATH I19
J 0
(-10100 5250);
DISPLAY 1.212766 (-10100 5250);
PAINT GREEN (-10100 5250);
DISPLAY INVISIBLE (-10100 5250);
FORCEPROP 1 LAST TOLERANCE 10%
J 0
(-10150 5300);
DISPLAY 1.212766 (-10150 5300);
PAINT GREEN (-10150 5300);
DISPLAY INVISIBLE (-10150 5300);
FORCEPROP 1 LAST CLS_PN G105-0B104-EK
J 0
(-10100 5250);
DISPLAY 1.212766 (-10100 5250);
PAINT GREEN (-10100 5250);
DISPLAY INVISIBLE (-10100 5250);
FORCEPROP 1 LAST CDS_LMAN_SYM_OUTLINE -50,0,50,-50
J 0
(-10000 5200);
DISPLAY 0.468085 (-10000 5200);
PAINT GREEN (-10000 5200);
DISPLAY INVISIBLE (-10000 5200);
FORCEPROP 2 LAST CDS_LIB passive
J 0
(-10000 5200);
DISPLAY INVISIBLE (-10000 5200);
FORCEPROP 0 LAST PACKAGE 0402
J 0
(-9850 5400);
DISPLAY 1.021277 (-9850 5400);
FORCEPROP 0 LAST VOLTAGE 25V
J 0
(-9850 5500);
DISPLAY 1.021277 (-9850 5500);
FORCEPROP 1 LAST VALUE 0.1UF
J 0
(-9900 5150);
DISPLAY 1.212766 (-9900 5150);
PAINT GREEN (-9900 5150);
FORCEADD GND_SG..1
(-7250 2450);
FORCEPROP 3 LASTPIN (-7200 2500) SIG_NAME SG\g
J 0
(-7190 2510);
DISPLAY 0.659574 (-7190 2510);
PAINT MONO (-7190 2510);
DISPLAY INVISIBLE (-7190 2510);
FORCEPROP 1 LAST PATH I20
J 0
(-7215 2450);
DISPLAY 0.808511 (-7215 2450);
PAINT GREEN (-7215 2450);
DISPLAY INVISIBLE (-7215 2450);
FORCEPROP 1 LAST BODY_TYPE PLUMBING
J 0
(-7235 2435);
DISPLAY 0.808511 (-7235 2435);
PAINT GREEN (-7235 2435);
DISPLAY INVISIBLE (-7235 2435);
FORCEPROP 1 LAST CDS_LMAN_SYM_OUTLINE 0,0,100,-50
J 0
(-7250 2450);
DISPLAY 0.468085 (-7250 2450);
PAINT GREEN (-7250 2450);
DISPLAY INVISIBLE (-7250 2450);
FORCEPROP 2 LAST CDS_LIB cls
J 0
(-7250 2450);
DISPLAY INVISIBLE (-7250 2450);
FORCEPROP 1 LAST HDL_POWER SG
J 1
(-7195 2355);
DISPLAY 0.808511 (-7195 2355);
PAINT GREEN (-7195 2355);
FORCEADD RESISTOR..1
(-6300 4550);
FORCEPROP 1 LAST $LOCATION R250
J 2
(-6501 4555);
DISPLAY 1.212766 (-6501 4555);
PAINT GREEN (-6501 4555);
FORCEPROP 0 LAST CDS_LOCATION R250
J 0
(-6100 4650);
DISPLAY INVISIBLE (-6100 4650);
FORCEPROP 0 LAST $SEC 1
J 0
(-6100 4650);
DISPLAY 0.680851 (-6100 4650);
PAINT MONO (-6100 4650);
DISPLAY INVISIBLE (-6100 4650);
FORCEPROP 0 LAST CDS_SEC 1
J 0
(-6100 4650);
DISPLAY 1.021277 (-6100 4650);
DISPLAY INVISIBLE (-6100 4650);
FORCEPROP 0 LASTPIN (-6400 4550) $PN 1
J 2
(-6410 4560);
DISPLAY 0.680851 (-6410 4560);
PAINT MONO (-6410 4560);
FORCEPROP 0 LASTPIN (-6150 4550) $PN 2
J 0
(-6140 4560);
DISPLAY 0.680851 (-6140 4560);
PAINT MONO (-6140 4560);
FORCEPROP 1 LAST PATH I23
J 0
(-6497 4655);
DISPLAY 1.212766 (-6497 4655);
PAINT GREEN (-6497 4655);
DISPLAY INVISIBLE (-6497 4655);
FORCEPROP 1 LAST TOLERANCE -
J 0
(-6497 4805);
DISPLAY 1.212766 (-6497 4805);
PAINT GREEN (-6497 4805);
DISPLAY INVISIBLE (-6497 4805);
FORCEPROP 1 LAST CLS_PN G155-100R0-J0
J 0
(-6436 4750);
DISPLAY 1.212766 (-6436 4750);
PAINT GREEN (-6436 4750);
DISPLAY INVISIBLE (-6436 4750);
FORCEPROP 2 LAST CDS_LIB passive
J 0
(-6300 4550);
DISPLAY INVISIBLE (-6300 4550);
FORCEPROP 1 LAST CDS_LMAN_SYM_OUTLINE -50,50,100,-50
J 0
(-6300 4550);
DISPLAY 0.468085 (-6300 4550);
PAINT GREEN (-6300 4550);
DISPLAY INVISIBLE (-6300 4550);
FORCEPROP 1 LAST VALUE 0OHM
J 0
(-6050 4550);
DISPLAY 1.212766 (-6050 4550);
PAINT GREEN (-6050 4550);
FORCEPROP 0 LAST PACKAGE 0402
J 0
(-6350 4600);
DISPLAY 1.021277 (-6350 4600);
FORCEADD CAPACITOR..1
(-5400 4550);
FORCEPROP 1 LAST $LOCATION C265
J 2
(-5538 4550);
DISPLAY 1.212766 (-5538 4550);
PAINT GREEN (-5538 4550);
FORCEPROP 0 LAST CDS_LOCATION C265
J 0
(-4650 4750);
DISPLAY INVISIBLE (-4650 4750);
FORCEPROP 0 LAST $SEC 1
J 0
(-5150 4700);
DISPLAY 0.680851 (-5150 4700);
PAINT MONO (-5150 4700);
DISPLAY INVISIBLE (-5150 4700);
FORCEPROP 0 LAST CDS_SEC 1
J 0
(-5150 4700);
DISPLAY 1.021277 (-5150 4700);
DISPLAY INVISIBLE (-5150 4700);
FORCEPROP 0 LASTPIN (-5500 4550) $PN 1
J 2
(-5510 4560);
DISPLAY 0.680851 (-5510 4560);
PAINT MONO (-5510 4560);
FORCEPROP 0 LASTPIN (-5250 4550) $PN 2
J 0
(-5240 4560);
DISPLAY 0.680851 (-5240 4560);
PAINT MONO (-5240 4560);
FORCEPROP 1 LAST PATH I24
J 2
(-5450 4600);
DISPLAY 1.212766 (-5450 4600);
PAINT GREEN (-5450 4600);
DISPLAY INVISIBLE (-5450 4600);
FORCEPROP 1 LAST TOLERANCE 10%
J 2
(-5500 4650);
DISPLAY 1.212766 (-5500 4650);
PAINT GREEN (-5500 4650);
DISPLAY INVISIBLE (-5500 4650);
FORCEPROP 1 LAST CDS_LMAN_SYM_OUTLINE 0,50,50,-50
J 0
(-5400 4550);
DISPLAY 0.468085 (-5400 4550);
PAINT GREEN (-5400 4550);
DISPLAY INVISIBLE (-5400 4550);
FORCEPROP 2 LAST CDS_LIB passive
J 0
(-5400 4550);
DISPLAY INVISIBLE (-5400 4550);
FORCEPROP 1 LAST CLS_PN G105-0B104-EK
J 2
(-5450 4650);
DISPLAY 1.212766 (-5450 4650);
PAINT GREEN (-5450 4650);
DISPLAY INVISIBLE (-5450 4650);
FORCEPROP 2 LASTPIN (-5500 4550) SIG_NAME UN$523$CAPACITOR$I24$1
J 0
(-5490 4560);
DISPLAY 0.659574 (-5490 4560);
PAINT MONO (-5490 4560);
DISPLAY INVISIBLE (-5490 4560);
FORCEPROP 0 LAST VOLTAGE 25V
J 0
(-5450 4750);
DISPLAY 1.021277 (-5450 4750);
FORCEPROP 0 LAST PACKAGE 0402
J 0
(-5450 4650);
DISPLAY 1.021277 (-5450 4650);
FORCEPROP 1 LAST VALUE 0.1UF
J 0
(-5150 4550);
DISPLAY 1.212766 (-5150 4550);
PAINT GREEN (-5150 4550);
FORCEADD INDUCTOR_2..1
(-4050 4350);
FORCEPROP 1 LAST $LOCATION L5
J 2
(-4200 4400);
DISPLAY 1.212766 (-4200 4400);
PAINT GREEN (-4200 4400);
FORCEPROP 0 LAST CDS_LOCATION L5
J 0
(-3800 4450);
DISPLAY INVISIBLE (-3800 4450);
FORCEPROP 0 LAST $SEC 1
J 0
(-3850 4500);
DISPLAY 0.680851 (-3850 4500);
PAINT MONO (-3850 4500);
DISPLAY INVISIBLE (-3850 4500);
FORCEPROP 0 LAST CDS_SEC 1
J 0
(-3850 4500);
DISPLAY 1.021277 (-3850 4500);
DISPLAY INVISIBLE (-3850 4500);
FORCEPROP 0 LASTPIN (-4200 4350) $PN 1
J 2
(-4210 4360);
DISPLAY 0.680851 (-4210 4360);
PAINT MONO (-4210 4360);
FORCEPROP 0 LASTPIN (-3850 4350) $PN 2
J 0
(-3840 4360);
DISPLAY 0.680851 (-3840 4360);
PAINT MONO (-3840 4360);
FORCEPROP 1 LAST CDS_LMAN_SYM_OUTLINE -100,50,150,-50
J 0
(-4050 4350);
DISPLAY 0.468085 (-4050 4350);
PAINT GREEN (-4050 4350);
DISPLAY INVISIBLE (-4050 4350);
FORCEPROP 2 LAST CDS_LIB passive
J 0
(-4050 4350);
DISPLAY INVISIBLE (-4050 4350);
FORCEPROP 1 LAST TOLERANCE 20%
J 2
(-3844 4250);
DISPLAY 1.212766 (-3844 4250);
PAINT GREEN (-3844 4250);
DISPLAY INVISIBLE (-3844 4250);
FORCEPROP 1 LAST PATH I25
J 2
(-4150 4300);
DISPLAY 1.212766 (-4150 4300);
PAINT GREEN (-4150 4300);
DISPLAY INVISIBLE (-4150 4300);
FORCEPROP 1 LAST CLS_PN G190-10418-01
J 2
(-4094 4500);
DISPLAY 1.212766 (-4094 4500);
PAINT GREEN (-4094 4500);
DISPLAY INVISIBLE (-4094 4500);
FORCEPROP 1 LAST VALUE 1.0UH
J 0
(-3750 4400);
DISPLAY 1.212766 (-3750 4400);
PAINT GREEN (-3750 4400);
FORCEADD RESISTOR..1
(-3150 4700);
FORCEPROP 1 LAST $LOCATION R253
J 2
(-3350 4700);
DISPLAY 1.212766 (-3350 4700);
PAINT GREEN (-3350 4700);
FORCEPROP 0 LAST CDS_LOCATION R253
J 0
(-2900 4800);
DISPLAY INVISIBLE (-2900 4800);
FORCEPROP 0 LAST $SEC 1
J 0
(-3000 4850);
DISPLAY 0.680851 (-3000 4850);
PAINT MONO (-3000 4850);
DISPLAY INVISIBLE (-3000 4850);
FORCEPROP 0 LAST CDS_SEC 1
J 0
(-3000 4850);
DISPLAY 1.021277 (-3000 4850);
DISPLAY INVISIBLE (-3000 4850);
FORCEPROP 0 LASTPIN (-3250 4700) $PN 1
J 2
(-3260 4710);
DISPLAY 0.680851 (-3260 4710);
PAINT MONO (-3260 4710);
FORCEPROP 0 LASTPIN (-3000 4700) $PN 2
J 0
(-2990 4710);
DISPLAY 0.680851 (-2990 4710);
PAINT MONO (-2990 4710);
FORCEPROP 1 LAST PATH I26
J 0
(-3347 4805);
DISPLAY 1.212766 (-3347 4805);
PAINT GREEN (-3347 4805);
DISPLAY INVISIBLE (-3347 4805);
FORCEPROP 1 LAST TOLERANCE 1%
J 0
(-3347 4955);
DISPLAY 1.212766 (-3347 4955);
PAINT GREEN (-3347 4955);
DISPLAY INVISIBLE (-3347 4955);
FORCEPROP 2 LAST CDS_LIB passive
J 0
(-3150 4700);
DISPLAY INVISIBLE (-3150 4700);
FORCEPROP 1 LAST CDS_LMAN_SYM_OUTLINE -50,50,100,-50
J 0
(-3150 4700);
DISPLAY 0.468085 (-3150 4700);
PAINT GREEN (-3150 4700);
DISPLAY INVISIBLE (-3150 4700);
FORCEPROP 1 LAST CLS_PN G157-12R20-01
J 0
(-3286 4900);
DISPLAY 1.212766 (-3286 4900);
PAINT GREEN (-3286 4900);
DISPLAY INVISIBLE (-3286 4900);
FORCEPROP 0 LAST PACKAGE 0805
J 0
(-3200 4750);
DISPLAY 1.021277 (-3200 4750);
FORCEPROP 1 LAST VALUE 2.2OHM
J 0
(-2900 4700);
DISPLAY 1.212766 (-2900 4700);
PAINT GREEN (-2900 4700);
FORCEPROP 0 LAST NO_ASSY TRUE
J 0
(-3350 4600);
DISPLAY 1.021277 (-3350 4600);
DISPLAY BOTH (-3350 4600);
FORCEADD CAPACITOR..2
(-3150 3550);
FORCEPROP 1 LAST $LOCATION C267
J 0
(-3050 3700);
DISPLAY 1.212766 (-3050 3700);
PAINT GREEN (-3050 3700);
FORCEPROP 0 LAST CDS_LOCATION C267
J 0
(-3050 3800);
DISPLAY INVISIBLE (-3050 3800);
FORCEPROP 0 LAST $SEC 1
J 0
(-3100 3700);
DISPLAY 0.680851 (-3100 3700);
PAINT MONO (-3100 3700);
DISPLAY INVISIBLE (-3100 3700);
FORCEPROP 0 LAST CDS_SEC 1
J 0
(-3100 3700);
DISPLAY 1.021277 (-3100 3700);
DISPLAY INVISIBLE (-3100 3700);
FORCEPROP 0 LASTPIN (-3150 3650) $PN 1
R 1
J 0
(-3160 3660);
DISPLAY 0.680851 (-3160 3660);
PAINT MONO (-3160 3660);
FORCEPROP 0 LASTPIN (-3150 3400) $PN 2
R 1
J 2
(-3160 3390);
DISPLAY 0.680851 (-3160 3390);
PAINT MONO (-3160 3390);
FORCEPROP 1 LAST PATH I28
J 0
(-3250 3600);
DISPLAY 1.212766 (-3250 3600);
PAINT GREEN (-3250 3600);
DISPLAY INVISIBLE (-3250 3600);
FORCEPROP 1 LAST TOLERANCE 10%
J 0
(-3300 3650);
DISPLAY 1.212766 (-3300 3650);
PAINT GREEN (-3300 3650);
DISPLAY INVISIBLE (-3300 3650);
FORCEPROP 1 LAST CDS_LMAN_SYM_OUTLINE -50,0,50,-50
J 0
(-3150 3550);
DISPLAY 0.468085 (-3150 3550);
PAINT GREEN (-3150 3550);
DISPLAY INVISIBLE (-3150 3550);
FORCEPROP 2 LAST CDS_LIB passive
J 0
(-3150 3550);
DISPLAY INVISIBLE (-3150 3550);
FORCEPROP 1 LAST CLS_PN G104-0B101-FK
J 0
(-3250 3600);
DISPLAY 1.212766 (-3250 3600);
PAINT GREEN (-3250 3600);
DISPLAY INVISIBLE (-3250 3600);
FORCEPROP 2 LASTPIN (-3150 3650) SIG_NAME UN$523$CAPACITOR$I28$1
J 0
(-3140 3660);
DISPLAY 0.659574 (-3140 3660);
PAINT MONO (-3140 3660);
DISPLAY INVISIBLE (-3140 3660);
FORCEPROP 0 LAST PACKAGE 0201
J 0
(-3050 3450);
DISPLAY 1.021277 (-3050 3450);
FORCEPROP 1 LAST VALUE 100PF
J 0
(-3050 3600);
DISPLAY 1.212766 (-3050 3600);
PAINT GREEN (-3050 3600);
FORCEADD RESISTOR..2
(-2550 3600);
FORCEPROP 1 LAST $LOCATION R255
J 0
(-2500 3450);
DISPLAY 1.212766 (-2500 3450);
PAINT GREEN (-2500 3450);
FORCEPROP 0 LAST CDS_LOCATION R255
J 0
(-2500 3750);
DISPLAY INVISIBLE (-2500 3750);
FORCEPROP 0 LAST $SEC 1
J 0
(-2500 3750);
DISPLAY 0.680851 (-2500 3750);
PAINT MONO (-2500 3750);
DISPLAY INVISIBLE (-2500 3750);
FORCEPROP 0 LAST CDS_SEC 1
J 0
(-2500 3750);
DISPLAY 1.021277 (-2500 3750);
DISPLAY INVISIBLE (-2500 3750);
FORCEPROP 0 LASTPIN (-2550 3700) $PN 1
R 1
J 0
(-2560 3710);
DISPLAY 0.680851 (-2560 3710);
PAINT MONO (-2560 3710);
FORCEPROP 0 LASTPIN (-2550 3450) $PN 2
R 1
J 2
(-2560 3440);
DISPLAY 0.680851 (-2560 3440);
PAINT MONO (-2560 3440);
FORCEPROP 1 LAST PATH I29
J 0
(-2747 3705);
DISPLAY 1.212766 (-2747 3705);
PAINT GREEN (-2747 3705);
DISPLAY INVISIBLE (-2747 3705);
FORCEPROP 1 LAST TOLERANCE 1%
J 0
(-2747 3855);
DISPLAY 1.212766 (-2747 3855);
PAINT GREEN (-2747 3855);
DISPLAY INVISIBLE (-2747 3855);
FORCEPROP 1 LAST CLS_PN G155-02262-01
J 0
(-2686 3800);
DISPLAY 1.212766 (-2686 3800);
PAINT GREEN (-2686 3800);
DISPLAY INVISIBLE (-2686 3800);
FORCEPROP 1 LAST CDS_LMAN_SYM_OUTLINE -50,50,50,-100
J 0
(-2550 3600);
DISPLAY 0.468085 (-2550 3600);
PAINT GREEN (-2550 3600);
DISPLAY INVISIBLE (-2550 3600);
FORCEPROP 2 LAST CDS_LIB passive
J 0
(-2550 3600);
DISPLAY INVISIBLE (-2550 3600);
FORCEPROP 1 LAST VALUE 22.6K
J 0
(-2500 3650);
DISPLAY 1.212766 (-2500 3650);
PAINT GREEN (-2500 3650);
FORCEPROP 0 LAST PACKAGE 0402
J 0
(-2500 3800);
DISPLAY 1.021277 (-2500 3800);
FORCEADD RESISTOR..2
(-2550 4050);
FORCEPROP 1 LAST $LOCATION R254
J 0
(-2500 3900);
DISPLAY 1.212766 (-2500 3900);
PAINT GREEN (-2500 3900);
FORCEPROP 0 LAST CDS_LOCATION R254
J 0
(-2500 4200);
DISPLAY INVISIBLE (-2500 4200);
FORCEPROP 0 LAST $SEC 1
J 0
(-2500 4200);
DISPLAY 0.680851 (-2500 4200);
PAINT MONO (-2500 4200);
DISPLAY INVISIBLE (-2500 4200);
FORCEPROP 0 LAST CDS_SEC 1
J 0
(-2500 4200);
DISPLAY 1.021277 (-2500 4200);
DISPLAY INVISIBLE (-2500 4200);
FORCEPROP 0 LASTPIN (-2550 4150) $PN 1
R 1
J 0
(-2560 4160);
DISPLAY 0.680851 (-2560 4160);
PAINT MONO (-2560 4160);
FORCEPROP 0 LASTPIN (-2550 3900) $PN 2
R 1
J 2
(-2560 3890);
DISPLAY 0.680851 (-2560 3890);
PAINT MONO (-2560 3890);
FORCEPROP 1 LAST PATH I30
J 0
(-2747 4155);
DISPLAY 1.212766 (-2747 4155);
PAINT GREEN (-2747 4155);
DISPLAY INVISIBLE (-2747 4155);
FORCEPROP 1 LAST TOLERANCE 1%
J 0
(-2747 4305);
DISPLAY 1.212766 (-2747 4305);
PAINT GREEN (-2747 4305);
DISPLAY INVISIBLE (-2747 4305);
FORCEPROP 1 LAST CLS_PN G155-120R0-01
J 0
(-2686 4250);
DISPLAY 1.212766 (-2686 4250);
PAINT GREEN (-2686 4250);
DISPLAY INVISIBLE (-2686 4250);
FORCEPROP 1 LAST CDS_LMAN_SYM_OUTLINE -50,50,50,-100
J 0
(-2550 4050);
DISPLAY 0.468085 (-2550 4050);
PAINT GREEN (-2550 4050);
DISPLAY INVISIBLE (-2550 4050);
FORCEPROP 2 LAST CDS_LIB passive
J 0
(-2550 4050);
DISPLAY INVISIBLE (-2550 4050);
FORCEPROP 1 LAST VALUE 20OHM
J 0
(-2500 4100);
DISPLAY 1.212766 (-2500 4100);
PAINT GREEN (-2500 4100);
FORCEPROP 0 LAST PACKAGE 0402
J 0
(-2500 4250);
DISPLAY 1.021277 (-2500 4250);
FORCEADD CAPACITOR..1
(-4150 4700);
FORCEPROP 1 LAST $LOCATION C266
J 2
(-4250 4700);
DISPLAY 1.212766 (-4250 4700);
PAINT GREEN (-4250 4700);
FORCEPROP 0 LAST CDS_LOCATION C266
J 0
(-2900 4800);
DISPLAY INVISIBLE (-2900 4800);
FORCEPROP 0 LAST $SEC 1
J 0
(-3900 4850);
DISPLAY 0.680851 (-3900 4850);
PAINT MONO (-3900 4850);
DISPLAY INVISIBLE (-3900 4850);
FORCEPROP 0 LAST CDS_SEC 1
J 0
(-3900 4850);
DISPLAY 1.021277 (-3900 4850);
DISPLAY INVISIBLE (-3900 4850);
FORCEPROP 0 LASTPIN (-4250 4700) $PN 1
J 2
(-4260 4710);
DISPLAY 0.680851 (-4260 4710);
PAINT MONO (-4260 4710);
FORCEPROP 0 LASTPIN (-4000 4700) $PN 2
J 0
(-3990 4710);
DISPLAY 0.680851 (-3990 4710);
PAINT MONO (-3990 4710);
FORCEPROP 1 LAST PATH I31
J 2
(-4200 4750);
DISPLAY 1.212766 (-4200 4750);
PAINT GREEN (-4200 4750);
DISPLAY INVISIBLE (-4200 4750);
FORCEPROP 2 LASTPIN (-4000 4700) SIG_NAME UN$523$CAPACITOR$I31$2
J 0
(-3990 4710);
DISPLAY 0.659574 (-3990 4710);
PAINT MONO (-3990 4710);
DISPLAY INVISIBLE (-3990 4710);
FORCEPROP 1 LAST CLS_PN G105-0A102-FJ
J 2
(-4200 4800);
DISPLAY 1.212766 (-4200 4800);
PAINT GREEN (-4200 4800);
DISPLAY INVISIBLE (-4200 4800);
FORCEPROP 1 LAST CDS_LMAN_SYM_OUTLINE 0,50,50,-50
J 0
(-4150 4700);
DISPLAY 0.468085 (-4150 4700);
PAINT GREEN (-4150 4700);
DISPLAY INVISIBLE (-4150 4700);
FORCEPROP 2 LAST CDS_LIB passive
J 0
(-4150 4700);
DISPLAY INVISIBLE (-4150 4700);
FORCEPROP 1 LAST TOLERANCE 5%
J 2
(-4250 4800);
DISPLAY 1.212766 (-4250 4800);
PAINT GREEN (-4250 4800);
DISPLAY INVISIBLE (-4250 4800);
FORCEPROP 0 LAST PACKAGE 0402
J 0
(-4200 4800);
DISPLAY 1.021277 (-4200 4800);
FORCEPROP 1 LAST VALUE 1000PF
J 0
(-3850 4700);
DISPLAY 1.212766 (-3850 4700);
PAINT GREEN (-3850 4700);
FORCEPROP 0 LAST NO_ASSY TRUE
J 0
(-4300 4550);
DISPLAY 1.021277 (-4300 4550);
DISPLAY BOTH (-4300 4550);
FORCEPROP 0 LAST VOLTAGE 50V
J 0
(-4200 4900);
DISPLAY 1.021277 (-4200 4900);
FORCEADD GND_SG..1
(-2650 4550);
FORCEPROP 3 LASTPIN (-2600 4600) SIG_NAME SG\g
J 0
(-2590 4610);
DISPLAY 0.659574 (-2590 4610);
PAINT MONO (-2590 4610);
DISPLAY INVISIBLE (-2590 4610);
FORCEPROP 1 LAST PATH I32
J 0
(-2615 4550);
DISPLAY 0.808511 (-2615 4550);
PAINT GREEN (-2615 4550);
DISPLAY INVISIBLE (-2615 4550);
FORCEPROP 1 LAST BODY_TYPE PLUMBING
J 0
(-2635 4535);
DISPLAY 0.808511 (-2635 4535);
PAINT GREEN (-2635 4535);
DISPLAY INVISIBLE (-2635 4535);
FORCEPROP 2 LAST CDS_LIB cls
J 0
(-2650 4550);
DISPLAY INVISIBLE (-2650 4550);
FORCEPROP 1 LAST CDS_LMAN_SYM_OUTLINE 0,0,100,-50
J 0
(-2650 4550);
DISPLAY 0.468085 (-2650 4550);
PAINT GREEN (-2650 4550);
DISPLAY INVISIBLE (-2650 4550);
FORCEPROP 1 LAST HDL_POWER SG
J 1
(-2595 4455);
DISPLAY 0.808511 (-2595 4455);
PAINT GREEN (-2595 4455);
FORCEADD CAPACITOR..2
(-1850 4000);
FORCEPROP 1 LAST $LOCATION C268
J 0
(-1750 4050);
DISPLAY 1.212766 (-1750 4050);
PAINT GREEN (-1750 4050);
FORCEPROP 0 LAST CDS_LOCATION C268
J 0
(-1750 4250);
DISPLAY INVISIBLE (-1750 4250);
FORCEPROP 0 LAST $SEC 1
J 0
(-1800 4150);
DISPLAY 0.680851 (-1800 4150);
PAINT MONO (-1800 4150);
DISPLAY INVISIBLE (-1800 4150);
FORCEPROP 0 LAST CDS_SEC 1
J 0
(-1800 4150);
DISPLAY 1.021277 (-1800 4150);
DISPLAY INVISIBLE (-1800 4150);
FORCEPROP 0 LASTPIN (-1850 4100) $PN 1
R 1
J 0
(-1860 4110);
DISPLAY 0.680851 (-1860 4110);
PAINT MONO (-1860 4110);
FORCEPROP 0 LASTPIN (-1850 3850) $PN 2
R 1
J 2
(-1860 3840);
DISPLAY 0.680851 (-1860 3840);
PAINT MONO (-1860 3840);
FORCEPROP 1 LAST PATH I33
J 0
(-1950 4050);
DISPLAY 1.212766 (-1950 4050);
PAINT GREEN (-1950 4050);
DISPLAY INVISIBLE (-1950 4050);
FORCEPROP 1 LAST TOLERANCE 10%
J 0
(-2000 4100);
DISPLAY 1.212766 (-2000 4100);
PAINT GREEN (-2000 4100);
DISPLAY INVISIBLE (-2000 4100);
FORCEPROP 1 LAST CDS_LMAN_SYM_OUTLINE -50,0,50,-50
J 0
(-1850 4000);
DISPLAY 0.468085 (-1850 4000);
PAINT GREEN (-1850 4000);
DISPLAY INVISIBLE (-1850 4000);
FORCEPROP 2 LAST CDS_LIB passive
J 0
(-1850 4000);
DISPLAY INVISIBLE (-1850 4000);
FORCEPROP 1 LAST CLS_PN G105-0B104-CK
J 0
(-1950 4050);
DISPLAY 1.212766 (-1950 4050);
PAINT GREEN (-1950 4050);
DISPLAY INVISIBLE (-1950 4050);
FORCEPROP 0 LAST VOLTAGE 10V
J 0
(-1750 4300);
DISPLAY 1.021277 (-1750 4300);
FORCEPROP 0 LAST PACKAGE 0402
J 0
(-1750 4200);
DISPLAY 1.021277 (-1750 4200);
FORCEPROP 1 LAST VALUE 0.1UF
J 0
(-1750 3950);
DISPLAY 1.212766 (-1750 3950);
PAINT GREEN (-1750 3950);
FORCEADD CAPACITOR..2
(-1350 4000);
FORCEPROP 1 LAST $LOCATION C269
J 0
(-1250 4050);
DISPLAY 1.212766 (-1250 4050);
PAINT GREEN (-1250 4050);
FORCEPROP 0 LAST CDS_LOCATION C269
J 0
(-1250 4250);
DISPLAY INVISIBLE (-1250 4250);
FORCEPROP 0 LAST $SEC 1
J 0
(-1300 4150);
DISPLAY INVISIBLE (-1300 4150);
FORCEPROP 0 LAST CDS_SEC 1
J 0
(-1300 4150);
DISPLAY INVISIBLE (-1300 4150);
FORCEPROP 0 LASTPIN (-1350 4100) $PN 1
R 1
J 0
(-1360 4110);
DISPLAY 0.808511 (-1360 4110);
FORCEPROP 0 LASTPIN (-1350 3850) $PN 2
R 1
J 2
(-1360 3840);
DISPLAY 0.808511 (-1360 3840);
FORCEPROP 1 LAST PATH I34
J 0
(-1450 4050);
DISPLAY 1.212766 (-1450 4050);
PAINT GREEN (-1450 4050);
DISPLAY INVISIBLE (-1450 4050);
FORCEPROP 1 LAST CLS_PN G107-0F476-AM
J 0
(-1450 4050);
DISPLAY 1.212766 (-1450 4050);
PAINT GREEN (-1450 4050);
DISPLAY INVISIBLE (-1450 4050);
FORCEPROP 1 LAST CDS_LMAN_SYM_OUTLINE -50,0,50,-50
J 0
(-1350 4000);
DISPLAY 0.468085 (-1350 4000);
PAINT GREEN (-1350 4000);
DISPLAY INVISIBLE (-1350 4000);
FORCEPROP 2 LAST CDS_LIB passive
J 0
(-1350 4000);
DISPLAY INVISIBLE (-1350 4000);
FORCEPROP 1 LAST TOLERANCE 20%
J 0
(-1500 4100);
DISPLAY 1.212766 (-1500 4100);
PAINT GREEN (-1500 4100);
DISPLAY INVISIBLE (-1500 4100);
FORCEPROP 0 LAST VOLTAGE 4V
J 0
(-1250 4300);
DISPLAY 1.021277 (-1250 4300);
FORCEPROP 0 LAST PACKAGE 0805
J 0
(-1250 4200);
DISPLAY 1.021277 (-1250 4200);
FORCEPROP 1 LAST VALUE 47UF
J 0
(-1250 3950);
DISPLAY 1.212766 (-1250 3950);
PAINT GREEN (-1250 3950);
FORCEADD CAPACITOR..2
(-850 4000);
FORCEPROP 1 LAST $LOCATION C270
J 0
(-750 4050);
DISPLAY 1.212766 (-750 4050);
PAINT GREEN (-750 4050);
FORCEPROP 0 LAST CDS_LOCATION C270
J 0
(-750 4250);
DISPLAY INVISIBLE (-750 4250);
FORCEPROP 0 LAST $SEC 1
J 0
(-800 4150);
DISPLAY INVISIBLE (-800 4150);
FORCEPROP 0 LAST CDS_SEC 1
J 0
(-800 4150);
DISPLAY INVISIBLE (-800 4150);
FORCEPROP 0 LASTPIN (-850 4100) $PN 1
R 1
J 0
(-860 4110);
DISPLAY 0.808511 (-860 4110);
FORCEPROP 0 LASTPIN (-850 3850) $PN 2
R 1
J 2
(-860 3840);
DISPLAY 0.808511 (-860 3840);
FORCEPROP 1 LAST PATH I35
J 0
(-950 4050);
DISPLAY 1.212766 (-950 4050);
PAINT GREEN (-950 4050);
DISPLAY INVISIBLE (-950 4050);
FORCEPROP 1 LAST TOLERANCE 20%
J 0
(-1000 4100);
DISPLAY 1.212766 (-1000 4100);
PAINT GREEN (-1000 4100);
DISPLAY INVISIBLE (-1000 4100);
FORCEPROP 1 LAST CDS_LMAN_SYM_OUTLINE -50,0,50,-50
J 0
(-850 4000);
DISPLAY 0.468085 (-850 4000);
PAINT GREEN (-850 4000);
DISPLAY INVISIBLE (-850 4000);
FORCEPROP 2 LAST CDS_LIB passive
J 0
(-850 4000);
DISPLAY INVISIBLE (-850 4000);
FORCEPROP 1 LAST CLS_PN G107-0F476-AM
J 0
(-950 4050);
DISPLAY 1.212766 (-950 4050);
PAINT GREEN (-950 4050);
DISPLAY INVISIBLE (-950 4050);
FORCEPROP 0 LAST VOLTAGE 4V
J 0
(-750 4300);
DISPLAY 1.021277 (-750 4300);
FORCEPROP 0 LAST PACKAGE 0805
J 0
(-750 4200);
DISPLAY 1.021277 (-750 4200);
FORCEPROP 1 LAST VALUE 47UF
J 0
(-750 3950);
DISPLAY 1.212766 (-750 3950);
PAINT GREEN (-750 3950);
FORCEADD GND_SG..1
(-450 3150);
FORCEPROP 3 LASTPIN (-400 3200) SIG_NAME SG\g
J 0
(-390 3210);
DISPLAY 0.659574 (-390 3210);
PAINT MONO (-390 3210);
DISPLAY INVISIBLE (-390 3210);
FORCEPROP 1 LAST PATH I36
J 0
(-415 3150);
DISPLAY 0.808511 (-415 3150);
PAINT GREEN (-415 3150);
DISPLAY INVISIBLE (-415 3150);
FORCEPROP 1 LAST BODY_TYPE PLUMBING
J 0
(-435 3135);
DISPLAY 0.808511 (-435 3135);
PAINT GREEN (-435 3135);
DISPLAY INVISIBLE (-435 3135);
FORCEPROP 1 LAST CDS_LMAN_SYM_OUTLINE 0,0,100,-50
J 0
(-450 3150);
DISPLAY 0.468085 (-450 3150);
PAINT GREEN (-450 3150);
DISPLAY INVISIBLE (-450 3150);
FORCEPROP 2 LAST CDS_LIB cls
J 0
(-450 3150);
DISPLAY INVISIBLE (-450 3150);
FORCEPROP 1 LAST HDL_POWER SG
J 1
(-395 3055);
DISPLAY 0.808511 (-395 3055);
PAINT GREEN (-395 3055);
FORCEADD CAPACITOR..2
(-400 4000);
FORCEPROP 1 LAST $LOCATION C271
J 0
(-300 4050);
DISPLAY 1.212766 (-300 4050);
PAINT GREEN (-300 4050);
FORCEPROP 0 LAST CDS_LOCATION C271
J 0
(-300 4250);
DISPLAY INVISIBLE (-300 4250);
FORCEPROP 0 LAST $SEC 1
J 0
(-300 4250);
DISPLAY INVISIBLE (-300 4250);
FORCEPROP 0 LAST CDS_SEC 1
J 0
(-300 4250);
DISPLAY INVISIBLE (-300 4250);
FORCEPROP 0 LASTPIN (-400 4100) $PN 1
R 1
J 0
(-410 4110);
DISPLAY 0.808511 (-410 4110);
FORCEPROP 0 LASTPIN (-400 3850) $PN 2
R 1
J 2
(-410 3840);
DISPLAY 0.808511 (-410 3840);
FORCEPROP 1 LAST PATH I37
J 0
(-500 4050);
DISPLAY 1.212766 (-500 4050);
PAINT GREEN (-500 4050);
DISPLAY INVISIBLE (-500 4050);
FORCEPROP 1 LAST TOLERANCE 20%
J 0
(-550 4100);
DISPLAY 1.212766 (-550 4100);
PAINT GREEN (-550 4100);
DISPLAY INVISIBLE (-550 4100);
FORCEPROP 2 LAST CDS_LIB passive
J 0
(-400 4000);
DISPLAY INVISIBLE (-400 4000);
FORCEPROP 1 LAST CDS_LMAN_SYM_OUTLINE -50,0,50,-50
J 0
(-400 4000);
DISPLAY 0.468085 (-400 4000);
PAINT GREEN (-400 4000);
DISPLAY INVISIBLE (-400 4000);
FORCEPROP 1 LAST CLS_PN G107-0F476-AM
J 0
(-500 4050);
DISPLAY 1.212766 (-500 4050);
PAINT GREEN (-500 4050);
DISPLAY INVISIBLE (-500 4050);
FORCEPROP 0 LAST VOLTAGE 4V
J 0
(-300 4300);
DISPLAY 1.021277 (-300 4300);
FORCEPROP 0 LAST PACKAGE 0805
J 0
(-300 4200);
DISPLAY 1.021277 (-300 4200);
FORCEPROP 1 LAST VALUE 47UF
J 0
(-300 3950);
DISPLAY 1.212766 (-300 3950);
PAINT GREEN (-300 3950);
FORCEADD SOLDER_PREFORM..1
(-6150 2700);
FORCEPROP 1 LAST $LOCATION SP3
J 0
(-6100 2800);
DISPLAY 1.212766 (-6100 2800);
PAINT GREEN (-6100 2800);
FORCEPROP 0 LAST CDS_LOCATION SP3
J 0
(-6050 3100);
DISPLAY 1.021277 (-6050 3100);
DISPLAY INVISIBLE (-6050 3100);
FORCEPROP 0 LAST $SEC 1
J 0
(-6100 3000);
DISPLAY 0.680851 (-6100 3000);
PAINT MONO (-6100 3000);
DISPLAY INVISIBLE (-6100 3000);
FORCEPROP 0 LAST CDS_SEC 1
J 0
(-6050 3100);
DISPLAY 1.021277 (-6050 3100);
DISPLAY INVISIBLE (-6050 3100);
FORCEPROP 0 LASTPIN (-6250 2600) $PN 1
J 2
(-6260 2610);
DISPLAY 0.680851 (-6260 2610);
PAINT MONO (-6260 2610);
FORCEPROP 0 LASTPIN (-5800 2600) $PN 2
J 0
(-5790 2610);
DISPLAY 0.680851 (-5790 2610);
PAINT MONO (-5790 2610);
FORCEPROP 1 LAST PATH I39
J 0
(-6100 2750);
DISPLAY 1.212766 (-6100 2750);
PAINT GREEN (-6100 2750);
DISPLAY INVISIBLE (-6100 2750);
FORCEPROP 2 LAST CDS_LIB mech
J 0
(-6150 2700);
DISPLAY INVISIBLE (-6150 2700);
FORCEPROP 1 LAST CDS_LMAN_SYM_OUTLINE 0,0,250,-200
J 0
(-6150 2700);
DISPLAY 0.468085 (-6150 2700);
PAINT GREEN (-6150 2700);
DISPLAY INVISIBLE (-6150 2700);
FORCEPROP 1 LAST CLS_PN G380-10015-01
J 0
(-6100 2900);
DISPLAY 1.212766 (-6100 2900);
PAINT GREEN (-6100 2900);
FORCEADD VCC..1
(-13250 3750);
FORCEPROP 3 LASTPIN (-13200 3700) SIG_NAME XP3R3V\g
J 0
(-13190 3710);
DISPLAY 0.659574 (-13190 3710);
PAINT MONO (-13190 3710);
DISPLAY INVISIBLE (-13190 3710);
FORCEPROP 1 LAST PATH I43
J 0
(-13215 3840);
DISPLAY 0.808511 (-13215 3840);
PAINT GREEN (-13215 3840);
DISPLAY INVISIBLE (-13215 3840);
FORCEPROP 1 LAST BODY_TYPE PLUMBING
J 0
(-13295 3707);
DISPLAY 0.340426 (-13295 3707);
PAINT GREEN (-13295 3707);
DISPLAY INVISIBLE (-13295 3707);
FORCEPROP 1 LAST CDS_LMAN_SYM_OUTLINE -250,250,250,-250
J 0
(-13250 3750);
DISPLAY 0.468085 (-13250 3750);
PAINT GREEN (-13250 3750);
DISPLAY INVISIBLE (-13250 3750);
FORCEPROP 2 LAST CDS_LIB cls
J 0
(-13250 3750);
DISPLAY INVISIBLE (-13250 3750);
FORCEPROP 1 LAST HDL_POWER XP3R3V
J 1
(-13195 3805);
DISPLAY 1.021277 (-13195 3805);
PAINT GREEN (-13195 3805);
FORCEPROP 0 LAST VOLTAGE 3.3
J 0
(-13450 3850);
DISPLAY 1.021277 (-13450 3850);
DISPLAY BOTH (-13450 3850);
FORCEADD RESISTOR..2
(-13200 3350);
FORCEPROP 1 LAST $LOCATION R243
J 0
(-13150 3200);
DISPLAY 1.212766 (-13150 3200);
PAINT GREEN (-13150 3200);
FORCEPROP 0 LAST CDS_LOCATION R243
J 0
(-13150 3550);
DISPLAY 1.021277 (-13150 3550);
DISPLAY INVISIBLE (-13150 3550);
FORCEPROP 0 LAST $SEC 1
J 0
(-13150 3550);
DISPLAY 0.680851 (-13150 3550);
PAINT MONO (-13150 3550);
DISPLAY INVISIBLE (-13150 3550);
FORCEPROP 0 LAST CDS_SEC 1
J 0
(-13150 3550);
DISPLAY 1.021277 (-13150 3550);
DISPLAY INVISIBLE (-13150 3550);
FORCEPROP 0 LASTPIN (-13200 3450) $PN 1
R 1
J 0
(-13210 3460);
DISPLAY 0.680851 (-13210 3460);
PAINT MONO (-13210 3460);
FORCEPROP 0 LASTPIN (-13200 3200) $PN 2
R 1
J 2
(-13210 3190);
DISPLAY 0.680851 (-13210 3190);
PAINT MONO (-13210 3190);
FORCEPROP 1 LAST PATH I44
J 0
(-13397 3455);
DISPLAY 1.212766 (-13397 3455);
PAINT GREEN (-13397 3455);
DISPLAY INVISIBLE (-13397 3455);
FORCEPROP 1 LAST TOLERANCE 1%
J 0
(-13397 3605);
DISPLAY 1.212766 (-13397 3605);
PAINT GREEN (-13397 3605);
DISPLAY INVISIBLE (-13397 3605);
FORCEPROP 1 LAST CDS_LMAN_SYM_OUTLINE -50,50,50,-100
J 0
(-13200 3350);
DISPLAY 0.468085 (-13200 3350);
PAINT GREEN (-13200 3350);
DISPLAY INVISIBLE (-13200 3350);
FORCEPROP 2 LAST CDS_LIB passive
J 0
(-13200 3350);
DISPLAY INVISIBLE (-13200 3350);
FORCEPROP 1 LAST CLS_PN G155-14701-01
J 0
(-13336 3550);
DISPLAY 1.212766 (-13336 3550);
PAINT GREEN (-13336 3550);
DISPLAY INVISIBLE (-13336 3550);
FORCEPROP 1 LAST VALUE 4.7KOHM
J 0
(-13150 3450);
DISPLAY 1.212766 (-13150 3450);
PAINT GREEN (-13150 3450);
FORCEPROP 0 LAST PACKAGE 0402
J 0
(-13050 3350);
DISPLAY 1.021277 (-13050 3350);
FORCEADD GND_SG..1
(-13100 4850);
FORCEPROP 3 LASTPIN (-13050 4900) SIG_NAME SG\g
J 0
(-13040 4910);
DISPLAY 0.659574 (-13040 4910);
PAINT MONO (-13040 4910);
DISPLAY INVISIBLE (-13040 4910);
FORCEPROP 1 LAST PATH I45
J 0
(-13065 4850);
DISPLAY 0.808511 (-13065 4850);
PAINT GREEN (-13065 4850);
DISPLAY INVISIBLE (-13065 4850);
FORCEPROP 1 LAST BODY_TYPE PLUMBING
J 0
(-13085 4835);
DISPLAY 0.808511 (-13085 4835);
PAINT GREEN (-13085 4835);
DISPLAY INVISIBLE (-13085 4835);
FORCEPROP 2 LAST CDS_LIB cls
J 0
(-13100 4850);
DISPLAY INVISIBLE (-13100 4850);
FORCEPROP 1 LAST CDS_LMAN_SYM_OUTLINE 0,0,100,-50
J 0
(-13100 4850);
DISPLAY 0.468085 (-13100 4850);
PAINT GREEN (-13100 4850);
DISPLAY INVISIBLE (-13100 4850);
FORCEPROP 1 LAST HDL_POWER SG
J 1
(-13045 4755);
DISPLAY 0.808511 (-13045 4755);
PAINT GREEN (-13045 4755);
FORCEADD CAPACITOR..2
(-13050 5250);
FORCEPROP 1 LAST $LOCATION C255
J 0
(-12950 5150);
DISPLAY 1.212766 (-12950 5150);
PAINT GREEN (-12950 5150);
FORCEPROP 0 LAST CDS_LOCATION C255
J 0
(-12950 5500);
DISPLAY 1.021277 (-12950 5500);
DISPLAY INVISIBLE (-12950 5500);
FORCEPROP 0 LAST $SEC 1
J 0
(-12950 5500);
DISPLAY 0.680851 (-12950 5500);
PAINT MONO (-12950 5500);
DISPLAY INVISIBLE (-12950 5500);
FORCEPROP 0 LAST CDS_SEC 1
J 0
(-12950 5500);
DISPLAY 1.021277 (-12950 5500);
DISPLAY INVISIBLE (-12950 5500);
FORCEPROP 0 LASTPIN (-13050 5350) $PN 1
R 1
J 0
(-13060 5360);
DISPLAY 0.680851 (-13060 5360);
PAINT MONO (-13060 5360);
FORCEPROP 0 LASTPIN (-13050 5100) $PN 2
R 1
J 2
(-13060 5090);
DISPLAY 0.680851 (-13060 5090);
PAINT MONO (-13060 5090);
FORCEPROP 1 LAST PATH I46
J 0
(-13150 5300);
DISPLAY 1.212766 (-13150 5300);
PAINT GREEN (-13150 5300);
DISPLAY INVISIBLE (-13150 5300);
FORCEPROP 1 LAST TOLERANCE 10%
J 0
(-13200 5350);
DISPLAY 1.212766 (-13200 5350);
PAINT GREEN (-13200 5350);
DISPLAY INVISIBLE (-13200 5350);
FORCEPROP 1 LAST CLS_PN G105-0B104-EK
J 0
(-13150 5300);
DISPLAY 1.212766 (-13150 5300);
PAINT GREEN (-13150 5300);
DISPLAY INVISIBLE (-13150 5300);
FORCEPROP 1 LAST CDS_LMAN_SYM_OUTLINE -50,0,50,-50
J 0
(-13050 5250);
DISPLAY 0.468085 (-13050 5250);
PAINT GREEN (-13050 5250);
DISPLAY INVISIBLE (-13050 5250);
FORCEPROP 2 LAST CDS_LIB passive
J 0
(-13050 5250);
DISPLAY INVISIBLE (-13050 5250);
FORCEPROP 0 LAST PACKAGE 0402
J 0
(-12950 5250);
DISPLAY 1.021277 (-12950 5250);
FORCEPROP 1 LAST VALUE 0.1UF
J 0
(-12950 5050);
DISPLAY 1.212766 (-12950 5050);
PAINT GREEN (-12950 5050);
FORCEPROP 0 LAST VOLTAGE 25V
J 0
(-12950 5350);
DISPLAY 1.021277 (-12950 5350);
FORCEADD VCC..1
(-13100 5950);
FORCEPROP 3 LASTPIN (-13050 5900) SIG_NAME XP12R0V\g
J 0
(-13040 5910);
DISPLAY 0.659574 (-13040 5910);
PAINT MONO (-13040 5910);
DISPLAY INVISIBLE (-13040 5910);
FORCEPROP 1 LAST PATH I47
J 0
(-13065 6040);
DISPLAY 0.808511 (-13065 6040);
PAINT GREEN (-13065 6040);
DISPLAY INVISIBLE (-13065 6040);
FORCEPROP 1 LAST BODY_TYPE PLUMBING
J 0
(-13145 5907);
DISPLAY 0.340426 (-13145 5907);
PAINT GREEN (-13145 5907);
DISPLAY INVISIBLE (-13145 5907);
FORCEPROP 1 LAST CDS_LMAN_SYM_OUTLINE -250,250,250,-250
J 0
(-13100 5950);
DISPLAY 0.468085 (-13100 5950);
PAINT GREEN (-13100 5950);
DISPLAY INVISIBLE (-13100 5950);
FORCEPROP 2 LAST CDS_LIB cls
J 0
(-13100 5950);
DISPLAY INVISIBLE (-13100 5950);
FORCEPROP 1 LAST HDL_POWER XP12R0V
J 1
(-13045 6005);
DISPLAY 1.021277 (-13045 6005);
PAINT GREEN (-13045 6005);
FORCEPROP 0 LAST VOLTAGE 12V
J 0
(-13300 6050);
DISPLAY 1.021277 (-13300 6050);
DISPLAY BOTH (-13300 6050);
FORCEADD FERRITEBEAD..1
(-12550 5550);
FORCEPROP 1 LAST $LOCATION L9
J 2
(-12610 5609);
DISPLAY 1.212766 (-12610 5609);
PAINT GREEN (-12610 5609);
FORCEPROP 0 LAST CDS_LOCATION L9
J 0
(-12600 5700);
DISPLAY 1.021277 (-12600 5700);
DISPLAY INVISIBLE (-12600 5700);
FORCEPROP 0 LAST $SEC 1
J 0
(-12600 5700);
DISPLAY 0.680851 (-12600 5700);
PAINT MONO (-12600 5700);
DISPLAY INVISIBLE (-12600 5700);
FORCEPROP 0 LAST CDS_SEC 1
J 0
(-12600 5700);
DISPLAY 1.021277 (-12600 5700);
DISPLAY INVISIBLE (-12600 5700);
FORCEPROP 0 LASTPIN (-12650 5500) $PN 1
J 2
(-12660 5510);
DISPLAY 0.680851 (-12660 5510);
PAINT MONO (-12660 5510);
FORCEPROP 0 LASTPIN (-12250 5500) $PN 2
J 0
(-12240 5510);
DISPLAY 0.680851 (-12240 5510);
PAINT MONO (-12240 5510);
FORCEPROP 1 LAST CLS_PN G191-10101-01
J 2
(-12600 5600);
DISPLAY 1.212766 (-12600 5600);
PAINT GREEN (-12600 5600);
DISPLAY INVISIBLE (-12600 5600);
FORCEPROP 1 LAST TOLERANCE 25%
J 0
(-12650 5600);
DISPLAY 1.212766 (-12650 5600);
PAINT GREEN (-12650 5600);
DISPLAY INVISIBLE (-12650 5600);
FORCEPROP 1 LAST PATH I48
J 2
(-12600 5600);
DISPLAY 1.212766 (-12600 5600);
PAINT GREEN (-12600 5600);
DISPLAY INVISIBLE (-12600 5600);
FORCEPROP 1 LAST CDS_LMAN_SYM_OUTLINE 0,0,200,-100
J 0
(-12550 5550);
DISPLAY 0.468085 (-12550 5550);
PAINT GREEN (-12550 5550);
DISPLAY INVISIBLE (-12550 5550);
FORCEPROP 2 LAST CDS_LIB passive
J 0
(-12550 5550);
DISPLAY INVISIBLE (-12550 5550);
FORCEPROP 1 LAST VALUE 26OHM
J 0
(-12200 5500);
DISPLAY 1.212766 (-12200 5500);
PAINT GREEN (-12200 5500);
FORCEPROP 0 LAST PACKAGE 0603
J 0
(-12500 5600);
DISPLAY 1.021277 (-12500 5600);
FORCEADD CAPACITOR..1
R 1
(-11550 2600);
FORCEPROP 1 LAST $LOCATION C258
R 1
J 2
(-11650 2700);
DISPLAY 1.212766 (-11650 2700);
PAINT GREEN (-11650 2700);
FORCEPROP 0 LAST CDS_LOCATION C258
R 1
J 0
(-11450 2800);
DISPLAY 1.021277 (-11450 2800);
DISPLAY INVISIBLE (-11450 2800);
FORCEPROP 0 LAST $SEC 1
R 1
J 0
(-11450 2800);
DISPLAY 0.680851 (-11450 2800);
PAINT MONO (-11450 2800);
DISPLAY INVISIBLE (-11450 2800);
FORCEPROP 0 LAST CDS_SEC 1
R 1
J 0
(-11450 2800);
DISPLAY 1.021277 (-11450 2800);
DISPLAY INVISIBLE (-11450 2800);
FORCEPROP 0 LASTPIN (-11550 2500) $PN 1
R 1
J 2
(-11560 2490);
DISPLAY 0.680851 (-11560 2490);
PAINT MONO (-11560 2490);
FORCEPROP 0 LASTPIN (-11550 2750) $PN 2
R 1
J 0
(-11560 2760);
DISPLAY 0.680851 (-11560 2760);
PAINT MONO (-11560 2760);
FORCEPROP 1 LAST PATH I50
R 1
J 2
(-11600 2550);
DISPLAY 1.212766 (-11600 2550);
PAINT GREEN (-11600 2550);
DISPLAY INVISIBLE (-11600 2550);
FORCEPROP 1 LAST TOLERANCE 10%
R 1
J 2
(-11650 2500);
DISPLAY 1.212766 (-11650 2500);
PAINT GREEN (-11650 2500);
DISPLAY INVISIBLE (-11650 2500);
FORCEPROP 1 LAST CLS_PN G104-0B103-EK
R 1
J 2
(-11650 2550);
DISPLAY 1.212766 (-11650 2550);
PAINT GREEN (-11650 2550);
DISPLAY INVISIBLE (-11650 2550);
FORCEPROP 1 LAST CDS_LMAN_SYM_OUTLINE 0,50,50,-50
R 1
J 0
(-11550 2600);
DISPLAY 0.468085 (-11550 2600);
PAINT GREEN (-11550 2600);
DISPLAY INVISIBLE (-11550 2600);
FORCEPROP 2 LAST CDS_LIB passive
J 0
(-11550 2600);
DISPLAY INVISIBLE (-11550 2600);
FORCEPROP 0 LAST VOLTAGE 25V
J 0
(-11450 2750);
DISPLAY 1.021277 (-11450 2750);
FORCEPROP 1 LAST VALUE 0.01UF
J 0
(-11450 2600);
DISPLAY 1.212766 (-11450 2600);
PAINT GREEN (-11450 2600);
FORCEPROP 0 LAST PACKAGE 0402
J 0
(-11450 2500);
DISPLAY 1.021277 (-11450 2500);
FORCEADD RESISTOR..2
(-12150 3850);
FORCEPROP 1 LAST $LOCATION R246
J 0
(-12100 3700);
DISPLAY 1.212766 (-12100 3700);
PAINT GREEN (-12100 3700);
FORCEPROP 0 LAST CDS_LOCATION R246
J 0
(-12600 3950);
DISPLAY 1.021277 (-12600 3950);
DISPLAY INVISIBLE (-12600 3950);
FORCEPROP 0 LAST $SEC 1
J 0
(-12600 3950);
DISPLAY 0.680851 (-12600 3950);
PAINT MONO (-12600 3950);
DISPLAY INVISIBLE (-12600 3950);
FORCEPROP 0 LAST CDS_SEC 1
J 0
(-12600 3950);
DISPLAY 1.021277 (-12600 3950);
DISPLAY INVISIBLE (-12600 3950);
FORCEPROP 0 LASTPIN (-12150 3950) $PN 1
R 1
J 0
(-12160 3960);
DISPLAY 0.680851 (-12160 3960);
PAINT MONO (-12160 3960);
FORCEPROP 0 LASTPIN (-12150 3700) $PN 2
R 1
J 2
(-12160 3690);
DISPLAY 0.680851 (-12160 3690);
PAINT MONO (-12160 3690);
FORCEPROP 1 LAST PATH I51
J 0
(-12347 3955);
DISPLAY 1.212766 (-12347 3955);
PAINT GREEN (-12347 3955);
DISPLAY INVISIBLE (-12347 3955);
FORCEPROP 1 LAST TOLERANCE 1%
J 0
(-12347 4105);
DISPLAY 1.212766 (-12347 4105);
PAINT GREEN (-12347 4105);
DISPLAY INVISIBLE (-12347 4105);
FORCEPROP 2 LAST CDS_LIB passive
J 0
(-12150 3850);
DISPLAY INVISIBLE (-12150 3850);
FORCEPROP 1 LAST CDS_LMAN_SYM_OUTLINE -50,50,50,-100
J 0
(-12150 3850);
DISPLAY 0.468085 (-12150 3850);
PAINT GREEN (-12150 3850);
DISPLAY INVISIBLE (-12150 3850);
FORCEPROP 1 LAST CLS_PN A155-05101-DL
J 0
(-12286 4050);
DISPLAY 1.212766 (-12286 4050);
PAINT GREEN (-12286 4050);
DISPLAY INVISIBLE (-12286 4050);
FORCEPROP 0 LAST NO_ASSY TRUE
J 0
(-12750 3750);
DISPLAY 1.021277 (-12750 3750);
DISPLAY BOTH (-12750 3750);
FORCEPROP 1 LAST VALUE 5.1KOHM
J 0
(-12600 3850);
DISPLAY 1.212766 (-12600 3850);
PAINT GREEN (-12600 3850);
FORCEPROP 0 LAST PACKAGE 0402
J 0
(-12450 3950);
DISPLAY 1.021277 (-12450 3950);
FORCEADD RESISTOR..2
(-12000 4950);
FORCEPROP 1 LAST $LOCATION R247
J 0
(-11950 4800);
DISPLAY 1.212766 (-11950 4800);
PAINT GREEN (-11950 4800);
FORCEPROP 0 LAST CDS_LOCATION R247
J 0
(-12400 5050);
DISPLAY 1.021277 (-12400 5050);
DISPLAY INVISIBLE (-12400 5050);
FORCEPROP 0 LAST $SEC 1
J 0
(-12400 5050);
DISPLAY 0.680851 (-12400 5050);
PAINT MONO (-12400 5050);
DISPLAY INVISIBLE (-12400 5050);
FORCEPROP 0 LAST CDS_SEC 1
J 0
(-12400 5050);
DISPLAY 1.021277 (-12400 5050);
DISPLAY INVISIBLE (-12400 5050);
FORCEPROP 0 LASTPIN (-12000 5050) $PN 1
R 1
J 0
(-12010 5060);
DISPLAY 0.680851 (-12010 5060);
PAINT MONO (-12010 5060);
FORCEPROP 0 LASTPIN (-12000 4800) $PN 2
R 1
J 2
(-12010 4790);
DISPLAY 0.680851 (-12010 4790);
PAINT MONO (-12010 4790);
FORCEPROP 1 LAST PATH I54
J 0
(-12197 5055);
DISPLAY 1.212766 (-12197 5055);
PAINT GREEN (-12197 5055);
DISPLAY INVISIBLE (-12197 5055);
FORCEPROP 1 LAST TOLERANCE 1%
J 0
(-12197 5205);
DISPLAY 1.212766 (-12197 5205);
PAINT GREEN (-12197 5205);
DISPLAY INVISIBLE (-12197 5205);
FORCEPROP 1 LAST CLS_PN G155-11002-01
J 0
(-12136 5150);
DISPLAY 1.212766 (-12136 5150);
PAINT GREEN (-12136 5150);
DISPLAY INVISIBLE (-12136 5150);
FORCEPROP 1 LAST CDS_LMAN_SYM_OUTLINE -50,50,50,-100
J 0
(-12000 4950);
DISPLAY 0.468085 (-12000 4950);
PAINT GREEN (-12000 4950);
DISPLAY INVISIBLE (-12000 4950);
FORCEPROP 2 LAST CDS_LIB passive
J 0
(-12000 4950);
DISPLAY INVISIBLE (-12000 4950);
FORCEPROP 1 LAST VALUE 10KOHM
J 0
(-12400 4950);
DISPLAY 1.212766 (-12400 4950);
PAINT GREEN (-12400 4950);
FORCEPROP 0 LAST PACKAGE 0402
J 0
(-12350 5050);
DISPLAY 1.021277 (-12350 5050);
FORCEPROP 0 LAST NO_ASSY TRUE
J 0
(-12650 4850);
DISPLAY 1.021277 (-12650 4850);
DISPLAY BOTH (-12650 4850);
FORCEADD RESISTOR..1
R 1
(-4600 2900);
FORCEPROP 1 LAST $LOCATION R251
R 1
J 2
(-4655 2999);
DISPLAY 1.212766 (-4655 2999);
PAINT GREEN (-4655 2999);
FORCEPROP 0 LAST CDS_LOCATION R251
R 1
J 0
(-4550 3100);
DISPLAY 1.021277 (-4550 3100);
DISPLAY INVISIBLE (-4550 3100);
FORCEPROP 0 LAST $SEC 1
R 1
J 0
(-4550 3100);
DISPLAY 0.680851 (-4550 3100);
PAINT MONO (-4550 3100);
DISPLAY INVISIBLE (-4550 3100);
FORCEPROP 0 LAST CDS_SEC 1
R 1
J 0
(-4550 3100);
DISPLAY 1.021277 (-4550 3100);
DISPLAY INVISIBLE (-4550 3100);
FORCEPROP 0 LASTPIN (-4600 2800) $PN 1
R 1
J 2
(-4610 2790);
DISPLAY 0.680851 (-4610 2790);
PAINT MONO (-4610 2790);
FORCEPROP 0 LASTPIN (-4600 3050) $PN 2
R 1
J 0
(-4610 3060);
DISPLAY 0.680851 (-4610 3060);
PAINT MONO (-4610 3060);
FORCEPROP 1 LAST PATH I56
R 1
J 0
(-4705 2703);
DISPLAY 1.212766 (-4705 2703);
PAINT GREEN (-4705 2703);
DISPLAY INVISIBLE (-4705 2703);
FORCEPROP 1 LAST TOLERANCE 1%
R 1
J 0
(-4855 2703);
DISPLAY 1.212766 (-4855 2703);
PAINT GREEN (-4855 2703);
DISPLAY INVISIBLE (-4855 2703);
FORCEPROP 1 LAST CLS_PN G155-03322-01
R 1
J 0
(-4800 2764);
DISPLAY 1.212766 (-4800 2764);
PAINT GREEN (-4800 2764);
DISPLAY INVISIBLE (-4800 2764);
FORCEPROP 2 LAST CDS_LIB passive
J 0
(-4600 2900);
DISPLAY INVISIBLE (-4600 2900);
FORCEPROP 1 LAST CDS_LMAN_SYM_OUTLINE -50,50,100,-50
R 1
J 0
(-4600 2900);
DISPLAY 0.468085 (-4600 2900);
PAINT GREEN (-4600 2900);
DISPLAY INVISIBLE (-4600 2900);
FORCEPROP 1 LAST VALUE 33.2KOHM
R 1
J 0
(-4505 2789);
DISPLAY 1.212766 (-4505 2789);
PAINT GREEN (-4505 2789);
FORCEPROP 0 LAST PACKAGE 0402
R 1
J 0
(-4700 3000);
DISPLAY 1.021277 (-4700 3000);
FORCEADD RESISTOR..1
R 1
(-4250 2900);
FORCEPROP 1 LAST $LOCATION R252
R 1
J 2
(-4305 2999);
DISPLAY 1.212766 (-4305 2999);
PAINT GREEN (-4305 2999);
FORCEPROP 0 LAST CDS_LOCATION R252
R 1
J 0
(-4100 3000);
DISPLAY 1.021277 (-4100 3000);
DISPLAY INVISIBLE (-4100 3000);
FORCEPROP 0 LAST $SEC 1
R 1
J 0
(-4100 3000);
DISPLAY 0.680851 (-4100 3000);
PAINT MONO (-4100 3000);
DISPLAY INVISIBLE (-4100 3000);
FORCEPROP 0 LAST CDS_SEC 1
R 1
J 0
(-4100 3000);
DISPLAY 1.021277 (-4100 3000);
DISPLAY INVISIBLE (-4100 3000);
FORCEPROP 0 LASTPIN (-4250 2800) $PN 1
R 1
J 2
(-4260 2790);
DISPLAY 0.680851 (-4260 2790);
PAINT MONO (-4260 2790);
FORCEPROP 0 LASTPIN (-4250 3050) $PN 2
R 1
J 0
(-4260 3060);
DISPLAY 0.680851 (-4260 3060);
PAINT MONO (-4260 3060);
FORCEPROP 1 LAST PATH I57
R 1
J 0
(-4355 2703);
DISPLAY 1.212766 (-4355 2703);
PAINT GREEN (-4355 2703);
DISPLAY INVISIBLE (-4355 2703);
FORCEPROP 1 LAST TOLERANCE -
R 1
J 0
(-4505 2703);
DISPLAY 1.212766 (-4505 2703);
PAINT GREEN (-4505 2703);
DISPLAY INVISIBLE (-4505 2703);
FORCEPROP 1 LAST CLS_PN G156-100R0-J0
R 1
J 0
(-4450 2764);
DISPLAY 1.212766 (-4450 2764);
PAINT GREEN (-4450 2764);
DISPLAY INVISIBLE (-4450 2764);
FORCEPROP 1 LAST CDS_LMAN_SYM_OUTLINE -50,50,100,-50
R 1
J 0
(-4250 2900);
DISPLAY 0.468085 (-4250 2900);
PAINT GREEN (-4250 2900);
DISPLAY INVISIBLE (-4250 2900);
FORCEPROP 2 LAST CDS_LIB passive
R 1
J 0
(-4250 2900);
DISPLAY INVISIBLE (-4250 2900);
FORCEPROP 1 LAST VALUE 0OHM
R 1
J 0
(-4150 2850);
DISPLAY 1.212766 (-4150 2850);
PAINT GREEN (-4150 2850);
FORCEPROP 0 LAST PACKAGE 0603
R 1
J 0
(-4050 2700);
DISPLAY 1.021277 (-4050 2700);
FORCEPROP 0 LAST NO_ASSY TRUE
J 0
(-4100 2950);
DISPLAY 1.021277 (-4100 2950);
DISPLAY BOTH (-4100 2950);
FORCEADD GND_SG..1
(-11850 3300);
FORCEPROP 3 LASTPIN (-11800 3350) SIG_NAME SG\g
J 0
(-11790 3360);
DISPLAY 0.659574 (-11790 3360);
PAINT MONO (-11790 3360);
DISPLAY INVISIBLE (-11790 3360);
FORCEPROP 1 LAST PATH I6
J 0
(-11815 3300);
DISPLAY 0.808511 (-11815 3300);
PAINT GREEN (-11815 3300);
DISPLAY INVISIBLE (-11815 3300);
FORCEPROP 1 LAST BODY_TYPE PLUMBING
J 0
(-11835 3285);
DISPLAY 0.808511 (-11835 3285);
PAINT GREEN (-11835 3285);
DISPLAY INVISIBLE (-11835 3285);
FORCEPROP 2 LAST CDS_LIB cls
J 0
(-11850 3300);
DISPLAY INVISIBLE (-11850 3300);
FORCEPROP 1 LAST CDS_LMAN_SYM_OUTLINE 0,0,100,-50
J 0
(-11850 3300);
DISPLAY 0.468085 (-11850 3300);
PAINT GREEN (-11850 3300);
DISPLAY INVISIBLE (-11850 3300);
FORCEPROP 1 LAST HDL_POWER SG
J 1
(-11795 3205);
DISPLAY 0.808511 (-11795 3205);
PAINT GREEN (-11795 3205);
FORCEADD CAPACITOR..2
(-11800 3850);
FORCEPROP 1 LAST $LOCATION C256
J 0
(-11700 3900);
DISPLAY 1.212766 (-11700 3900);
PAINT GREEN (-11700 3900);
FORCEPROP 0 LAST CDS_LOCATION C256
J 0
(-11700 4100);
DISPLAY INVISIBLE (-11700 4100);
FORCEPROP 0 LAST $SEC 1
J 0
(-11750 4000);
PAINT MONO (-11750 4000);
DISPLAY INVISIBLE (-11750 4000);
FORCEPROP 0 LAST CDS_SEC 1
J 0
(-11750 4000);
PAINT MONO (-11750 4000);
DISPLAY INVISIBLE (-11750 4000);
FORCEPROP 0 LASTPIN (-11800 3950) $PN 1
R 1
J 0
(-11810 3960);
DISPLAY 0.808511 (-11810 3960);
PAINT MONO (-11810 3960);
FORCEPROP 0 LASTPIN (-11800 3700) $PN 2
R 1
J 2
(-11810 3690);
DISPLAY 0.808511 (-11810 3690);
PAINT MONO (-11810 3690);
FORCEPROP 1 LAST PATH I7
J 0
(-11900 3900);
DISPLAY 1.212766 (-11900 3900);
PAINT GREEN (-11900 3900);
DISPLAY INVISIBLE (-11900 3900);
FORCEPROP 1 LAST TOLERANCE 10%
J 0
(-11950 3950);
DISPLAY 1.212766 (-11950 3950);
PAINT GREEN (-11950 3950);
DISPLAY INVISIBLE (-11950 3950);
FORCEPROP 1 LAST CLS_PN G105-0B104-CK
J 0
(-11900 3900);
DISPLAY 1.212766 (-11900 3900);
PAINT GREEN (-11900 3900);
DISPLAY INVISIBLE (-11900 3900);
FORCEPROP 2 LAST CDS_LIB passive
J 0
(-11800 3850);
DISPLAY INVISIBLE (-11800 3850);
FORCEPROP 1 LAST CDS_LMAN_SYM_OUTLINE -50,0,50,-50
J 0
(-11800 3850);
DISPLAY 0.468085 (-11800 3850);
PAINT GREEN (-11800 3850);
DISPLAY INVISIBLE (-11800 3850);
FORCEPROP 2 LASTPIN (-11800 3950) SIG_NAME UN$523$CAPACITOR$I7$1
J 0
(-11790 3960);
DISPLAY 0.659574 (-11790 3960);
PAINT MONO (-11790 3960);
DISPLAY INVISIBLE (-11790 3960);
FORCEPROP 0 LAST PACKAGE 0402
J 0
(-11700 4050);
DISPLAY 1.021277 (-11700 4050);
FORCEPROP 0 LAST VOLTAGE 10V
J 0
(-11700 4150);
DISPLAY 1.021277 (-11700 4150);
FORCEPROP 1 LAST VALUE 0.1UF
J 0
(-11700 3700);
DISPLAY 1.212766 (-11700 3700);
PAINT GREEN (-11700 3700);
FORCEADD CAPACITOR..2
(-9850 2950);
FORCEPROP 1 LAST $LOCATION C263
J 0
(-9800 3000);
DISPLAY 1.212766 (-9800 3000);
PAINT GREEN (-9800 3000);
FORCEPROP 0 LAST CDS_LOCATION C263
J 0
(-9800 2800);
DISPLAY 1.212766 (-9800 2800);
PAINT GREEN (-9800 2800);
DISPLAY INVISIBLE (-9800 2800);
FORCEPROP 0 LAST $SEC 1
J 0
(-9800 3100);
DISPLAY 0.680851 (-9800 3100);
PAINT MONO (-9800 3100);
DISPLAY INVISIBLE (-9800 3100);
FORCEPROP 0 LAST CDS_SEC 1
J 0
(-9800 3100);
DISPLAY 1.021277 (-9800 3100);
DISPLAY INVISIBLE (-9800 3100);
FORCEPROP 0 LASTPIN (-9850 3050) $PN 1
R 1
J 0
(-9860 3060);
DISPLAY 0.680851 (-9860 3060);
PAINT MONO (-9860 3060);
FORCEPROP 0 LASTPIN (-9850 2800) $PN 2
R 1
J 2
(-9860 2790);
DISPLAY 0.680851 (-9860 2790);
PAINT MONO (-9860 2790);
FORCEPROP 1 LAST CLS_PN G104-0B472-EK
J 0
(-9950 3000);
DISPLAY 1.212766 (-9950 3000);
PAINT GREEN (-9950 3000);
DISPLAY INVISIBLE (-9950 3000);
FORCEPROP 1 LAST PATH I9
J 0
(-9950 3000);
DISPLAY 1.212766 (-9950 3000);
PAINT GREEN (-9950 3000);
DISPLAY INVISIBLE (-9950 3000);
FORCEPROP 1 LAST TOLERANCE 10%
J 0
(-10000 3050);
DISPLAY 1.212766 (-10000 3050);
PAINT GREEN (-10000 3050);
DISPLAY INVISIBLE (-10000 3050);
FORCEPROP 1 LAST CDS_LMAN_SYM_OUTLINE -50,0,50,-50
J 0
(-9850 2950);
DISPLAY 0.468085 (-9850 2950);
PAINT GREEN (-9850 2950);
DISPLAY INVISIBLE (-9850 2950);
FORCEPROP 2 LAST CDS_LIB passive
J 0
(-9850 2950);
DISPLAY INVISIBLE (-9850 2950);
FORCEPROP 2 LASTPIN (-9850 3050) SIG_NAME UN$523$CAPACITOR$I9$1
J 0
(-9840 3060);
DISPLAY 0.659574 (-9840 3060);
PAINT MONO (-9840 3060);
DISPLAY INVISIBLE (-9840 3060);
FORCEPROP 1 LAST VALUE 4700PF
J 0
(-9800 2800);
DISPLAY 1.212766 (-9800 2800);
PAINT GREEN (-9800 2800);
FORCEPROP 0 LAST VOLTAGE 25V
J 0
(-9600 3000);
DISPLAY 1.021277 (-9600 3000);
FORCEPROP 0 LAST PACKAGE 0402
J 0
(-9750 2900);
DISPLAY 1.021277 (-9750 2900);
FORCEADD VCC..1
(-450 4800);
FORCEPROP 3 LASTPIN (-400 4750) SIG_NAME XP1R0V_FPGA\g
J 0
(-390 4760);
DISPLAY 0.659574 (-390 4760);
PAINT MONO (-390 4760);
DISPLAY INVISIBLE (-390 4760);
FORCEPROP 1 LAST PATH I97
J 0
(-415 4890);
DISPLAY 0.808511 (-415 4890);
PAINT GREEN (-415 4890);
DISPLAY INVISIBLE (-415 4890);
FORCEPROP 1 LAST BODY_TYPE PLUMBING
J 0
(-495 4757);
DISPLAY 0.340426 (-495 4757);
PAINT GREEN (-495 4757);
DISPLAY INVISIBLE (-495 4757);
FORCEPROP 1 LAST CDS_LMAN_SYM_OUTLINE -250,250,250,-250
J 0
(-450 4800);
DISPLAY 0.468085 (-450 4800);
PAINT GREEN (-450 4800);
DISPLAY INVISIBLE (-450 4800);
FORCEPROP 2 LAST CDS_LIB cls
J 0
(-450 4800);
DISPLAY INVISIBLE (-450 4800);
FORCEPROP 1 LAST HDL_POWER XP1R0V_FPGA
J 1
(-390 4840);
DISPLAY 1.021277 (-390 4840);
PAINT GREEN (-390 4840);
FORCEPROP 0 LAST VOLTAGE 1.0V
J 0
(-690 4940);
DISPLAY 1.021277 (-690 4940);
DISPLAY BOTH (-690 4940);
FORCEADD SHEET_A1_ENTERPRISE..1
(1150 -2450);
FORCEPROP 2 LAST CUSTOM_TXT_CDS <XR_PAGE_TITLE>
J 0
(-14420 8900);
DISPLAY 0.638298 (-14420 8900);
PAINT PINK (-14420 8900);
FORCEPROP 1 LAST CUSTOM_TXT_CDS <TITLE>
J 1
(-1010 -2170);
DISPLAY 0.978723 (-1010 -2170);
FORCEPROP 1 LAST CUSTOM_TXT_CDS <DOCNO>
J 0
(-1125 -2315);
DISPLAY 0.978723 (-1125 -2315);
FORCEPROP 1 LAST CUSTOM_TXT_CDS <DATE>
J 0
(-1200 -2425);
DISPLAY 0.978723 (-1200 -2425);
FORCEPROP 1 LAST CUSTOM_TXT_CDS <DESIGNER>
J 0
(-1200 -2025);
DISPLAY 0.978723 (-1200 -2025);
FORCEPROP 1 LAST CUSTOM_TXT_CDS <DOCREV>
J 0
(-200 -2350);
DISPLAY 0.978723 (-200 -2350);
FORCEPROP 1 LAST CUSTOM_TXT_CDS <CON_PAGE_NUM>
J 0
(595 -2350);
DISPLAY 0.978723 (595 -2350);
FORCEPROP 1 LAST CUSTOM_TXT_CDS <CON_TOTAL_PAGES>
J 0
(905 -2350);
DISPLAY 0.808511 (905 -2350);
FORCEPROP 1 LAST COMMENT_BODY TRUE
J 0
(1160 -2395);
DISPLAY 0.808511 (1160 -2395);
DISPLAY INVISIBLE (1160 -2395);
FORCEPROP 1 LAST CDS_LMAN_SYM_OUTLINE -15850,11300,200,-200
J 0
(1150 -2450);
DISPLAY 0.468085 (1150 -2450);
PAINT GREEN (1150 -2450);
DISPLAY INVISIBLE (1150 -2450);
FORCEPROP 2 LAST CDS_LIB cls
J 0
(1150 -2450);
DISPLAY INVISIBLE (1150 -2450);
FORCEPROP 2 LAST PAGE_BORDER TRUE
J 0
(-14420 8900);
DISPLAY 0.638298 (-14420 8900);
PAINT PINK (-14420 8900);
DISPLAY INVISIBLE (-14420 8900);
FORCEPROP 1 LAST TITLE XP1R0V_FPGA
J 0
(-235 -2150);
DISPLAY 1.212766 (-235 -2150);
PAINT GREEN (-235 -2150);
FORCEPROP 2 LAST CDS_XR_PAGE_TITLE CR-29 : @TIMECARD_LIB.TIMECARD(SCH_1):PAGE29
J 0
(-14420 8900);
DISPLAY 0.638298 (-14420 8900);
PAINT PINK (-14420 8900);
DISPLAY INVISIBLE (-14420 8900);
WIRE 16 -1 (-11550 2500)(-11550 2350);
WIRE 16 -1 (-3000 4700)(-2600 4700);
WIRE 16 -1 (-2600 4700)(-2600 4600);
WIRE 16 -1 (-13200 3450)(-13200 3700);
WIRE 16 -1 (-13050 5100)(-13050 4900);
WIRE 16 -1 (-13450 2500)(-12400 2500);
FORCEPROP 2 LAST SIG_NAME XP1R0V_FPGA_PG
J 0
(-13410 2510);
DISPLAY 1.021277 (-13410 2510);
WIRE 16 -1 (-13200 3200)(-13200 2950);
WIRE 16 -1 (-13200 2950)(-11950 2950);
WIRE 16 -1 (-11950 2500)(-11950 2950);
WIRE 16 -1 (-11550 2950)(-11950 2950);
WIRE 16 -1 (-11300 2950)(-11550 2950);
WIRE 16 -1 (-11550 2750)(-11550 2950);
WIRE 16 -1 (-12150 2500)(-11950 2500);
WIRE 16 -1 (-11300 2950)(-11300 4050);
FORCEPROP 2 LAST SIG_NAME XP1R0V_PG
J 0
(-9760 4060);
DISPLAY 1.021277 (-9760 4060);
WIRE 16 -1 (-11300 4050)(-8750 4050);
WIRE 16 -1 (-1850 4350)(-2550 4350);
WIRE 16 -1 (-1850 4100)(-1850 4350);
WIRE 16 -1 (-1850 4350)(-1350 4350);
WIRE 16 -1 (-2550 4150)(-2550 4350);
WIRE 16 -1 (-2550 4350)(-3850 4350);
WIRE 16 -1 (-1350 4350)(-850 4350);
WIRE 16 -1 (-1350 4100)(-1350 4350);
WIRE 16 -1 (-850 4350)(-400 4350);
WIRE 16 -1 (-850 4100)(-850 4350);
WIRE 16 -1 (-400 4750)(-400 4350);
WIRE 16 -1 (-400 4100)(-400 4350);
WIRE 16 -1 (-12150 3700)(-12150 3500);
WIRE 16 -1 (-12150 3500)(-11800 3500);
WIRE 16 -1 (-11800 3500)(-11800 3700);
WIRE 16 -1 (-11800 3350)(-11800 3500);
WIRE 16 -1 (-13050 5350)(-13050 5500);
WIRE 16 -1 (-13050 5500)(-12650 5500);
WIRE 16 -1 (-13050 5900)(-13050 5500);
WIRE 16 -1 (-1850 3850)(-1850 3650);
WIRE 16 -1 (-1850 3650)(-1350 3650);
WIRE 16 -1 (-1350 3650)(-850 3650);
WIRE 16 -1 (-1350 3850)(-1350 3650);
WIRE 16 -1 (-850 3650)(-400 3650);
WIRE 16 -1 (-850 3850)(-850 3650);
WIRE 16 -1 (-400 3650)(-400 3850);
WIRE 16 -1 (-400 3650)(-400 3200);
WIRE 16 -1 (-7550 3550)(-7200 3550);
WIRE 16 -1 (-7200 3550)(-7200 3450);
WIRE 16 -1 (-7200 3450)(-7200 3350);
WIRE 16 -1 (-7550 3450)(-7200 3450);
WIRE 16 -1 (-7200 3350)(-7200 3250);
WIRE 16 -1 (-7550 3350)(-7200 3350);
WIRE 16 -1 (-7200 3250)(-7200 3150);
WIRE 16 -1 (-7550 3250)(-7200 3250);
WIRE 16 -1 (-7550 3150)(-7200 3150);
WIRE 16 -1 (-7200 3150)(-7200 3050);
WIRE 16 -1 (-7200 3050)(-7200 2600);
WIRE 16 -1 (-7550 3050)(-7200 3050);
WIRE 16 -1 (-6250 2600)(-7200 2600);
WIRE 16 -1 (-7200 2600)(-7200 2500);
WIRE 16 -1 (-11450 5050)(-11450 4850);
WIRE 16 -1 (-11450 4850)(-11000 4850);
WIRE 16 -1 (-10550 4850)(-11000 4850);
WIRE 16 -1 (-11000 4850)(-11000 5050);
WIRE 16 -1 (-10000 4850)(-10550 4850);
WIRE 16 -1 (-10550 5050)(-10550 4850);
WIRE 16 -1 (-10000 5050)(-10000 4850);
WIRE 16 -1 (-10000 4700)(-10000 4850);
WIRE 16 -1 (-11050 3200)(-11050 2700);
WIRE 16 -1 (-11050 2700)(-10500 2700);
WIRE 16 -1 (-9850 2700)(-10500 2700);
FORCEPROP 2 LAST SIG_NAME XP1R0V_AGND
J 0
(-10410 2610);
DISPLAY 1.021277 (-10410 2610);
WIRE 16 -1 (-10500 3200)(-10500 2700);
WIRE 16 -1 (-9250 2700)(-9850 2700);
WIRE 16 -1 (-9850 2800)(-9850 2700);
WIRE 16 -1 (-8900 2700)(-9250 2700);
WIRE 16 -1 (-9250 2950)(-9250 2700);
WIRE 16 -1 (-8900 3050)(-8900 2700);
WIRE 16 -1 (-8900 3050)(-8750 3050);
WIRE 16 -1 (-11050 3450)(-11050 3850);
WIRE 16 -1 (-11050 3850)(-8750 3850);
FORCEPROP 2 LAST SIG_NAME XP1R0V_SS
J 0
(-9760 3860);
DISPLAY 1.021277 (-9760 3860);
WIRE 16 -1 (-2550 3450)(-2550 3200);
WIRE 16 -1 (-2550 3200)(-3150 3200);
WIRE 16 -1 (-3150 3400)(-3150 3200);
WIRE 16 -1 (-4250 3200)(-3150 3200);
WIRE 16 -1 (-4600 3200)(-4250 3200);
WIRE 16 -1 (-4250 3050)(-4250 3200);
WIRE 16 -1 (-4600 3850)(-4600 3200);
WIRE 16 -1 (-4600 3050)(-4600 3200);
WIRE 16 -1 (-7550 3850)(-4600 3850);
FORCEPROP 2 LAST SIG_NAME XP1R0V_FB_R_TO_AGND
J 1
(-6760 3860);
DISPLAY 1.021277 (-6760 3860);
WIRE 16 -1 (-3250 4700)(-4000 4700);
WIRE 16 -1 (-4250 4700)(-4550 4700);
WIRE 16 -1 (-4550 4350)(-4550 4700);
WIRE 16 -1 (-4550 4350)(-4200 4350);
WIRE 16 -1 (-4900 4350)(-4550 4350);
WIRE 16 -1 (-4900 4550)(-4900 4350);
WIRE 16 -1 (-7400 4350)(-4900 4350);
FORCEPROP 2 LAST SIG_NAME XP1R0V_SW
J 1
(-7010 4360);
DISPLAY 1.021277 (-7010 4360);
WIRE 16 -1 (-7400 4250)(-7400 4350);
WIRE 16 -1 (-7550 4350)(-7400 4350);
WIRE 16 -1 (-5250 4550)(-4900 4550);
WIRE 16 -1 (-7550 4250)(-7400 4250);
WIRE 16 -1 (-12000 5050)(-12000 5500);
WIRE 16 -1 (-11450 5500)(-12000 5500);
WIRE 16 -1 (-12250 5500)(-12000 5500);
WIRE 16 -1 (-11000 5500)(-11450 5500);
WIRE 16 -1 (-11450 5300)(-11450 5500);
WIRE 16 -1 (-10550 5500)(-11000 5500);
WIRE 16 -1 (-11000 5300)(-11000 5500);
WIRE 16 -1 (-10550 5500)(-10000 5500);
FORCEPROP 2 LAST SIG_NAME VIN_XP1R0V
J 0
(-9410 4560);
DISPLAY 1.021277 (-9410 4560);
WIRE 16 -1 (-10550 5300)(-10550 5500);
WIRE 16 -1 (-9500 5500)(-10000 5500);
WIRE 16 -1 (-10000 5300)(-10000 5500);
WIRE 16 -1 (-9500 5500)(-9500 4550);
WIRE 16 -1 (-9500 4550)(-8750 4550);
WIRE 16 -1 (-9500 4450)(-9500 4550);
WIRE 16 -1 (-8750 4450)(-9500 4450);
WIRE 16 -1 (-11800 3950)(-11800 4250);
WIRE 16 -1 (-8750 4250)(-11800 4250);
WIRE 16 -1 (-11800 4250)(-12000 4250);
WIRE 16 -1 (-12000 4800)(-12000 4250);
WIRE 16 -1 (-12150 4250)(-12000 4250);
WIRE 16 -1 (-12150 3950)(-12150 4250);
WIRE 16 -1 (-12450 4250)(-12150 4250);
WIRE 8 -1 (450 1100)(450 1250);
WIRE 8 -1 (450 1100)(-500 1100);
WIRE 8 -1 (450 1250)(-500 1250);
WIRE 8 -1 (450 1250)(450 1400);
WIRE 8 -1 (450 1400)(450 1550);
WIRE 8 -1 (450 1400)(-500 1400);
WIRE 8 -1 (-500 1100)(-500 1250);
WIRE 8 -1 (-500 1250)(-1350 1250);
WIRE 8 -1 (-500 1250)(-500 1400);
WIRE 8 -1 (-500 1100)(-1350 1100);
WIRE 8 -1 (-1350 1100)(-1350 1250);
WIRE 8 -1 (-500 1400)(-1350 1400);
WIRE 8 -1 (-500 1400)(-500 1550);
WIRE 8 -1 (-1350 1250)(-1350 1400);
WIRE 8 -1 (450 1550)(-500 1550);
WIRE 8 -1 (450 1550)(450 1700);
WIRE 8 -1 (450 1700)(450 1850);
WIRE 8 -1 (-500 1700)(450 1700);
WIRE 8 -1 (-500 1550)(-1350 1550);
WIRE 8 -1 (-500 1550)(-500 1700);
WIRE 8 -1 (-1350 1400)(-1350 1550);
WIRE 8 -1 (-1350 1550)(-1350 1700);
WIRE 8 -1 (-1350 1700)(-500 1700);
WIRE 8 -1 (-500 1700)(-500 1850);
WIRE 8 -1 (-500 1850)(450 1850);
WIRE 8 -1 (450 1850)(450 2000);
WIRE 8 -1 (450 2000)(450 2150);
WIRE 8 -1 (-500 2000)(450 2000);
WIRE 8 -1 (-1350 1850)(-500 1850);
WIRE 8 -1 (-500 1850)(-500 2000);
WIRE 8 -1 (-1350 1700)(-1350 1850);
WIRE 8 -1 (-1350 1850)(-1350 2000);
WIRE 8 -1 (-1350 2000)(-500 2000);
WIRE 8 -1 (-500 2000)(-500 2150);
WIRE 8 -1 (-500 2150)(450 2150);
WIRE 8 -1 (450 2300)(450 2150);
WIRE 8 -1 (450 2450)(450 2300);
WIRE 8 -1 (-500 2300)(450 2300);
WIRE 8 -1 (-1350 2150)(-500 2150);
WIRE 8 -1 (-500 2150)(-500 2300);
WIRE 8 -1 (-1350 2000)(-1350 2150);
WIRE 8 -1 (-1350 2300)(-1350 2150);
WIRE 8 -1 (-1350 2300)(-500 2300);
WIRE 8 -1 (-500 2300)(-500 2450);
WIRE 8 -1 (450 2450)(-500 2450);
WIRE 8 -1 (-500 2450)(-1350 2450);
WIRE 8 -1 (-1350 2450)(-1350 2300);
WIRE 16 -1 (-10500 3450)(-10500 3650);
WIRE 16 -1 (-8750 3650)(-10500 3650);
FORCEPROP 2 LAST SIG_NAME XP1R0V_RT
J 0
(-9760 3660);
DISPLAY 1.021277 (-9760 3660);
WIRE 16 -1 (-9250 3200)(-9250 3450);
WIRE 16 -1 (-9250 3450)(-8750 3450);
WIRE 16 -1 (-9850 3450)(-9250 3450);
FORCEPROP 2 LAST SIG_NAME XP1R0V_COMP
J 0
(-9410 3460);
DISPLAY 1.021277 (-9410 3460);
WIRE 16 -1 (-9850 3350)(-9850 3450);
WIRE 16 -1 (-9850 3100)(-9850 3050);
WIRE 16 -1 (-4250 2800)(-4250 2600);
WIRE 16 -1 (-4250 2600)(-4600 2600);
WIRE 16 -1 (-4600 2800)(-4600 2600);
WIRE 16 -1 (-5800 2600)(-4600 2600);
FORCEPROP 2 LAST SIG_NAME XP1R0V_AGND
J 0
(-5760 2510);
DISPLAY 1.021277 (-5760 2510);
WIRE 16 -1 (-2550 3800)(-3150 3800);
WIRE 16 -1 (-2550 3900)(-2550 3800);
WIRE 16 -1 (-2550 3800)(-2550 3700);
WIRE 16 -1 (-3150 3800)(-3150 3650);
WIRE 16 -1 (-13650 4250)(-12700 4250);
FORCEPROP 2 LAST SIG_NAME XP3R3V_PG
J 0
(-13610 4260);
DISPLAY 1.021277 (-13610 4260);
WIRE 16 -1 (-7550 4550)(-6400 4550);
FORCEPROP 2 LAST SIG_NAME XP1R0V_BT
J 1
(-7010 4560);
DISPLAY 1.021277 (-7010 4560);
WIRE 16 -1 (-6150 4550)(-5500 4550);
DOT 1 (-13050 5500);
DOT 1 (-7200 2600);
DOT 1 (-4600 2600);
DOT 1 (-1350 3650);
DOT 1 (-1350 4350);
DOT 1 (-11950 2950);
DOT 1 (-11550 2950);
DOT 1 (-12150 4250);
DOT 1 (-12000 4250);
DOT 1 (-12000 5500);
DOT 1 (-11800 3500);
DOT 1 (-11800 4250);
DOT 1 (-9250 3450);
DOT 1 (-11450 5500);
DOT 1 (-11000 4850);
DOT 1 (-11000 5500);
DOT 1 (-10550 5500);
DOT 1 (-9850 2700);
DOT 1 (-9250 2700);
DOT 1 (-10000 4850);
DOT 1 (-9500 4550);
DOT 1 (-10000 5500);
DOT 1 (-7200 3050);
DOT 1 (-7200 3250);
DOT 1 (-7200 3150);
DOT 1 (-7200 3350);
DOT 1 (-7200 3450);
DOT 1 (-7400 4350);
DOT 1 (-4600 3200);
DOT 1 (-4250 3200);
DOT 1 (-4900 4350);
DOT 1 (-4550 4350);
DOT 1 (-1350 1250);
DOT 1 (-1350 1400);
DOT 1 (-1350 1700);
DOT 1 (-1350 1550);
DOT 1 (-1350 1850);
DOT 1 (-1350 2000);
DOT 1 (-1350 2150);
DOT 1 (-500 1100);
DOT 1 (-500 1250);
DOT 1 (-500 1400);
DOT 1 (-500 1550);
DOT 1 (-500 1700);
DOT 1 (-500 2000);
DOT 1 (-500 2150);
DOT 1 (-1350 2300);
DOT 1 (-500 2300);
DOT 1 (-3150 3200);
DOT 1 (-2550 3800);
DOT 1 (-2550 4350);
DOT 1 (-1850 4350);
DOT 1 (-850 3650);
DOT 1 (-500 2450);
DOT 1 (-400 3650);
DOT 1 (-850 4350);
DOT 1 (-400 4350);
DOT 1 (450 1250);
DOT 1 (450 1400);
DOT 1 (450 1700);
DOT 1 (450 1550);
DOT 1 (450 1850);
DOT 1 (450 2000);
DOT 1 (450 2150);
DOT 1 (450 2300);
DOT 1 (-500 1850);
DOT 1 (-10550 4850);
DOT 1 (-10500 2700);
FORCENOTE
FSW
(-1050 1750) 0;
DISPLAY LEFT (-1050 1750);
DISPLAY 1.595745 (-1050 1750);
FORCENOTE
VFB=0.6V
(-3200 3100) 0;
DISPLAY LEFT (-3200 3100);
DISPLAY 1.021277 (-3200 3100);
FORCENOTE
XP1R0V 
(-8650 5400) 0;
DISPLAY LEFT (-8650 5400);
DISPLAY 3.148936 (-8650 5400);
FORCENOTE
108%*VOUT
(-350 1300) 0;
DISPLAY LEFT (-350 1300);
DISPLAY 1.595745 (-350 1300);
FORCENOTE
12V
(-150 2200) 0;
DISPLAY LEFT (-150 2200);
DISPLAY 1.595745 (-150 2200);
FORCENOTE
500KHZ
(-250 1750) 0;
DISPLAY LEFT (-250 1750);
DISPLAY 1.595745 (-250 1750);
FORCENOTE
 +/- 1%
(-300 1150) 0;
DISPLAY LEFT (-300 1150);
DISPLAY 1.595745 (-300 1150);
FORCENOTE
VIN
(-1050 2200) 0;
DISPLAY LEFT (-1050 2200);
DISPLAY 1.595745 (-1050 2200);
FORCENOTE
OVP
(-1050 1300) 0;
DISPLAY LEFT (-1050 1300);
DISPLAY 1.595745 (-1050 1300);
FORCENOTE
SS
(-1000 1900) 0;
DISPLAY LEFT (-1000 1900);
DISPLAY 1.595745 (-1000 1900);
FORCENOTE
OCP
(-1050 1450) 0;
DISPLAY LEFT (-1050 1450);
DISPLAY 1.595745 (-1050 1450);
FORCENOTE
VOUT
(-1100 2050) 0;
DISPLAY LEFT (-1100 2050);
DISPLAY 1.595745 (-1100 2050);
FORCENOTE
 RIPPLE
(-1250 1150) 0;
DISPLAY LEFT (-1250 1150);
DISPLAY 1.595745 (-1250 1150);
FORCENOTE
POWER RAIL
(-1300 2350) 0;
DISPLAY LEFT (-1300 2350);
DISPLAY 1.595745 (-1300 2350);
FORCENOTE
O.6A
(-800 4400) 0;
DISPLAY LEFT (-800 4400);
DISPLAY 1.595745 (-800 4400);
FORCENOTE
XP1R0V
(-250 2350) 0;
DISPLAY LEFT (-250 2350);
DISPLAY 1.595745 (-250 2350);
FORCENOTE
IMAX
(-1100 1600) 0;
DISPLAY LEFT (-1100 1600);
DISPLAY 1.595745 (-1100 1600);
FORCENOTE
10A
(-150 1450) 0;
DISPLAY LEFT (-150 1450);
DISPLAY 1.595745 (-150 1450);
FORCENOTE
O.6A
(-150 1600) 0;
DISPLAY LEFT (-150 1600);
DISPLAY 1.595745 (-150 1600);
FORCENOTE
2.5MS
(-200 1900) 0;
DISPLAY LEFT (-200 1900);
DISPLAY 1.595745 (-200 1900);
FORCENOTE
XP1R0V
(-250 2050) 0;
DISPLAY LEFT (-250 2050);
DISPLAY 1.595745 (-250 2050);
FORCENOTE
XP1R0V_FPGA
(-1300 2500) 0;
DISPLAY LEFT (-1300 2500);
DISPLAY 1.595745 (-1300 2500);
PAINT VIOLET (-1300 2500);
FORCENOTE
XP1R0V_FPGA
(-8000 7500) 0;
DISPLAY LEFT (-8000 7500);
DISPLAY 4.914894 (-8000 7500);
FORCENOTE
G190-10418-01
(-4350 4250) 0;
DISPLAY LEFT (-4350 4250);
DISPLAY 1.021277 (-4350 4250);
PAINT SKYBLUE (-4350 4250);
QUIT
